FILE_TYPE = MACRO_DRAWING;
SET COLOR_WIRE YELLOW;
SET COLOR_PROP MONO;
SET COLOR_DOT WHITE;
SET COLOR_ARC YELLOW;
SET COLOR_BODY GREEN;
SET COLOR_NOTE MONO;
SET PROP_DISPLAY VALUE;
SET PAGE_NUMBER P102;
FORCEADD NB3W1200L..1
(350 2900);
FORCEPROP 1 LAST PART_NUMBER H13585-001
J 0
(-250 1850);
DISPLAY 0.617021 (-250 1850);
PAINT BLUE (-250 1850);
FORCEPROP 2 LASTPIN (-300 2350) $PN 9
J 2
(-310 2360);
DISPLAY 0.617021 (-310 2360);
PAINT ORANGE (-310 2360);
FORCEPROP 2 LASTPIN (-300 3150) $PN 12
J 2
(-310 3160);
DISPLAY 0.617021 (-310 3160);
PAINT ORANGE (-310 3160);
FORCEPROP 2 LASTPIN (-300 3300) $PN 11
J 2
(-310 3310);
DISPLAY 0.617021 (-310 3310);
PAINT ORANGE (-310 3310);
FORCEPROP 2 LASTPIN (-300 2900) $PN 53
J 2
(-310 2910);
DISPLAY 0.617021 (-310 2910);
PAINT ORANGE (-310 2910);
FORCEPROP 2 LASTPIN (-300 3800) $PN 1
J 2
(-310 3810);
DISPLAY 0.617021 (-310 3810);
PAINT ORANGE (-310 3810);
FORCEPROP 1 LAST MATERIAL IC
J 0
(-250 3950);
DISPLAY 0.617021 (-250 3950);
PAINT SKYBLUE (-250 3950);
FORCEPROP 2 LASTPIN (1000 3700) $PN 3
J 0
(1010 3710);
DISPLAY 0.617021 (1010 3710);
PAINT ORANGE (1010 3710);
FORCEPROP 2 LASTPIN (1000 2300) $PN 2
J 0
(1010 2310);
DISPLAY 0.617021 (1010 2310);
PAINT ORANGE (1010 2310);
FORCEPROP 2 LASTPIN (1000 2250) $PN 58
J 0
(1010 2260);
DISPLAY 0.617021 (1010 2260);
PAINT ORANGE (1010 2260);
FORCEPROP 2 LASTPIN (1000 2150) $PN 41
J 0
(1010 2160);
DISPLAY 0.617021 (1010 2160);
PAINT ORANGE (1010 2160);
FORCEPROP 2 LASTPIN (1000 2100) $PN 33
J 0
(1010 2110);
DISPLAY 0.617021 (1010 2110);
PAINT ORANGE (1010 2110);
FORCEPROP 2 LASTPIN (1000 2050) $PN 23
J 0
(1010 2060);
DISPLAY 0.617021 (1010 2060);
PAINT ORANGE (1010 2060);
FORCEPROP 2 LASTPIN (1000 2000) $PN 7
J 0
(1010 2010);
DISPLAY 0.617021 (1010 2010);
PAINT ORANGE (1010 2010);
FORCEPROP 2 LASTPIN (1000 3550) $PN 64
J 0
(1010 3560);
DISPLAY 0.617021 (1010 3560);
PAINT ORANGE (1010 3560);
FORCEPROP 2 LASTPIN (1000 3500) $PN 59
J 0
(1010 3510);
DISPLAY 0.617021 (1010 3510);
PAINT ORANGE (1010 3510);
FORCEPROP 2 LASTPIN (1000 3450) $PN 60
J 0
(1010 3460);
DISPLAY 0.617021 (1010 3460);
PAINT ORANGE (1010 3460);
FORCEPROP 2 LASTPIN (1000 3400) $PN 54
J 0
(1010 3410);
DISPLAY 0.617021 (1010 3410);
PAINT ORANGE (1010 3410);
FORCEPROP 2 LASTPIN (1000 3350) $PN 55
J 0
(1010 3360);
DISPLAY 0.617021 (1010 3360);
PAINT ORANGE (1010 3360);
FORCEPROP 2 LASTPIN (1000 3300) $PN 50
J 0
(1010 3310);
DISPLAY 0.617021 (1010 3310);
PAINT ORANGE (1010 3310);
FORCEPROP 2 LASTPIN (1000 3250) $PN 51
J 0
(1010 3260);
DISPLAY 0.617021 (1010 3260);
PAINT ORANGE (1010 3260);
FORCEPROP 2 LASTPIN (1000 3200) $PN 46
J 0
(1010 3210);
DISPLAY 0.617021 (1010 3210);
PAINT ORANGE (1010 3210);
FORCEPROP 2 LASTPIN (1000 3150) $PN 47
J 0
(1010 3160);
DISPLAY 0.617021 (1010 3160);
PAINT ORANGE (1010 3160);
FORCEPROP 2 LASTPIN (1000 3050) $PN 43
J 0
(1010 3060);
DISPLAY 0.617021 (1010 3060);
PAINT ORANGE (1010 3060);
FORCEPROP 2 LASTPIN (1000 2950) $PN 39
J 0
(1010 2960);
DISPLAY 0.617021 (1010 2960);
PAINT ORANGE (1010 2960);
FORCEPROP 2 LASTPIN (1000 2900) $PN 34
J 0
(1010 2910);
DISPLAY 0.617021 (1010 2910);
PAINT ORANGE (1010 2910);
FORCEPROP 2 LASTPIN (1000 2850) $PN 35
J 0
(1010 2860);
DISPLAY 0.617021 (1010 2860);
PAINT ORANGE (1010 2860);
FORCEPROP 2 LASTPIN (1000 2750) $PN 31
J 0
(1010 2760);
DISPLAY 0.617021 (1010 2760);
PAINT ORANGE (1010 2760);
FORCEPROP 2 LASTPIN (1000 2700) $PN 26
J 0
(1010 2710);
DISPLAY 0.617021 (1010 2710);
PAINT ORANGE (1010 2710);
FORCEPROP 2 LASTPIN (1000 2650) $PN 27
J 0
(1010 2660);
DISPLAY 0.617021 (1010 2660);
PAINT ORANGE (1010 2660);
FORCEPROP 2 LASTPIN (1000 2600) $PN 21
J 0
(1010 2610);
DISPLAY 0.617021 (1010 2610);
PAINT ORANGE (1010 2610);
FORCEPROP 2 LASTPIN (1000 2550) $PN 22
J 0
(1010 2560);
DISPLAY 0.617021 (1010 2560);
PAINT ORANGE (1010 2560);
FORCEPROP 2 LASTPIN (1000 2500) $PN 17
J 0
(1010 2510);
DISPLAY 0.617021 (1010 2510);
PAINT ORANGE (1010 2510);
FORCEPROP 2 LASTPIN (1000 1950) $PN 65
J 0
(1010 1960);
DISPLAY 0.617021 (1010 1960);
PAINT ORANGE (1010 1960);
FORCEPROP 2 LASTPIN (-300 3550) $PN 49
J 2
(-310 3560);
DISPLAY 0.617021 (-310 3560);
PAINT ORANGE (-310 3560);
FORCEPROP 2 LASTPIN (-300 3600) $PN 56
J 2
(-310 3610);
DISPLAY 0.617021 (-310 3610);
PAINT ORANGE (-310 3610);
FORCEPROP 2 LASTPIN (-300 3700) $PN 40
J 2
(-310 3710);
DISPLAY 0.617021 (-310 3710);
PAINT ORANGE (-310 3710);
FORCEPROP 2 LASTPIN (-300 3650) $PN 24
J 2
(-310 3660);
DISPLAY 0.617021 (-310 3660);
PAINT ORANGE (-310 3660);
FORCEPROP 2 LASTPIN (-300 3250) $PN 14
J 2
(-310 3260);
DISPLAY 0.617021 (-310 3260);
PAINT ORANGE (-310 3260);
FORCEPROP 2 LASTPIN (-300 3400) $PN 8
J 2
(-310 3410);
DISPLAY 0.617021 (-310 3410);
PAINT ORANGE (-310 3410);
FORCEPROP 2 LASTPIN (1000 2450) $PN 18
J 0
(1010 2460);
DISPLAY 0.617021 (1010 2460);
PAINT ORANGE (1010 2460);
FORCEPROP 2 LASTPIN (1000 3000) $PN 38
J 0
(1010 3010);
DISPLAY 0.617021 (1010 3010);
PAINT ORANGE (1010 3010);
FORCEPROP 2 LASTPIN (1000 3750) $PN 16
J 0
(1010 3760);
DISPLAY 0.617021 (1010 3760);
PAINT ORANGE (1010 3760);
FORCEPROP 2 LASTPIN (1000 3800) $PN 15
J 0
(1010 3810);
DISPLAY 0.617021 (1010 3810);
PAINT ORANGE (1010 3810);
FORCEPROP 2 LASTPIN (1000 3100) $PN 42
J 0
(1010 3110);
DISPLAY 0.617021 (1010 3110);
PAINT ORANGE (1010 3110);
FORCEPROP 2 LASTPIN (-300 3750) $PN 57
J 2
(-310 3760);
DISPLAY 0.617021 (-310 3760);
PAINT ORANGE (-310 3760);
FORCEPROP 2 LASTPIN (-300 3450) $PN 25
J 2
(-310 3460);
DISPLAY 0.617021 (-310 3460);
PAINT ORANGE (-310 3460);
FORCEPROP 2 LASTPIN (1000 3600) $PN 63
J 0
(1010 3610);
DISPLAY 0.617021 (1010 3610);
PAINT ORANGE (1010 3610);
FORCEPROP 2 LASTPIN (1000 2200) $PN 48
J 0
(1010 2210);
DISPLAY 0.617021 (1010 2210);
PAINT ORANGE (1010 2210);
FORCEPROP 2 LASTPIN (-300 2450) $PN 19
J 2
(-310 2460);
DISPLAY 0.617021 (-310 2460);
PAINT ORANGE (-310 2460);
FORCEPROP 2 LASTPIN (-300 2500) $PN 20
J 2
(-310 2510);
DISPLAY 0.617021 (-310 2510);
PAINT ORANGE (-310 2510);
FORCEPROP 2 LASTPIN (-300 2550) $PN 28
J 2
(-310 2560);
DISPLAY 0.617021 (-310 2560);
PAINT ORANGE (-310 2560);
FORCEPROP 2 LASTPIN (-300 2600) $PN 29
J 2
(-310 2610);
DISPLAY 0.617021 (-310 2610);
PAINT ORANGE (-310 2610);
FORCEPROP 2 LASTPIN (-300 2650) $PN 36
J 2
(-310 2660);
DISPLAY 0.617021 (-310 2660);
PAINT ORANGE (-310 2660);
FORCEPROP 2 LASTPIN (-300 2750) $PN 44
J 2
(-310 2760);
DISPLAY 0.617021 (-310 2760);
PAINT ORANGE (-310 2760);
FORCEPROP 2 LASTPIN (-300 2850) $PN 52
J 2
(-310 2860);
DISPLAY 0.617021 (-310 2860);
PAINT ORANGE (-310 2860);
FORCEPROP 2 LASTPIN (-300 2950) $PN 61
J 2
(-310 2960);
DISPLAY 0.617021 (-310 2960);
PAINT ORANGE (-310 2960);
FORCEPROP 2 LASTPIN (-300 3000) $PN 62
J 2
(-310 3010);
DISPLAY 0.617021 (-310 3010);
PAINT ORANGE (-310 3010);
FORCEPROP 2 LASTPIN (-300 2800) $PN 45
J 2
(-310 2810);
DISPLAY 0.617021 (-310 2810);
PAINT ORANGE (-310 2810);
FORCEPROP 2 LASTPIN (-300 3500) $PN 32
J 2
(-310 3510);
DISPLAY 0.617021 (-310 3510);
PAINT ORANGE (-310 3510);
FORCEPROP 2 LASTPIN (1000 2800) $PN 30
J 0
(1010 2810);
DISPLAY 0.617021 (1010 2810);
PAINT ORANGE (1010 2810);
FORCEPROP 2 LASTPIN (-300 2000) $PN 4
J 2
(-310 2010);
DISPLAY 0.617021 (-310 2010);
PAINT ORANGE (-310 2010);
FORCEPROP 2 LASTPIN (-300 2700) $PN 37
J 2
(-310 2710);
DISPLAY 0.617021 (-310 2710);
PAINT ORANGE (-310 2710);
FORCEPROP 2 LASTPIN (-300 2200) $PN 6
J 2
(-310 2210);
DISPLAY 0.617021 (-310 2210);
PAINT ORANGE (-310 2210);
FORCEPROP 2 LASTPIN (-300 2300) $PN 10
J 2
(-310 2310);
DISPLAY 0.617021 (-310 2310);
PAINT ORANGE (-310 2310);
FORCEPROP 2 LASTPIN (-300 2100) $PN 5
J 2
(-310 2110);
DISPLAY 0.617021 (-310 2110);
PAINT ORANGE (-310 2110);
FORCEPROP 1 LAST LOCATION EU4D2
J 0
(-250 4000);
DISPLAY 0.617021 (-250 4000);
PAINT AQUA (-250 4000);
FORCEPROP 2 LASTPIN (-300 3100) $PN 13
J 2
(-310 3110);
DISPLAY 0.617021 (-310 3110);
PAINT ORANGE (-310 3110);
FORCEPROP 1 LAST PATH I1
J 0
(350 3950);
PAINT GREEN (350 3950);
DISPLAY INVISIBLE (350 3950);
FORCEPROP 1 LAST CDS_LMAN_SYM_OUTLINE -600,1000,600,-1000
J 0
(350 2900);
DISPLAY 0.468085 (350 2900);
PAINT GREEN (350 2900);
DISPLAY INVISIBLE (350 2900);
FORCEPROP 2 LAST CDS_LIB mstr_clock
J 0
(350 2900);
PAINT MONO (350 2900);
DISPLAY INVISIBLE (350 2900);
FORCEPROP 1 LAST PACK_TYPE LCC
J 0
(-250 4050);
PAINT SKYBLUE (-250 4050);
DISPLAY INVISIBLE (-250 4050);
FORCEPROP 2 LAST BOM_COST SYS_CLOCK
J 0
(-250 4200);
DISPLAY 1.021277 (-250 4200);
PAINT ORANGE (-250 4200);
DISPLAY INVISIBLE (-250 4200);
FORCEPROP 2 LAST SEC_TYPE LCC
J 0
(-250 4050);
DISPLAY 1.021277 (-250 4050);
PAINT ORANGE (-250 4050);
DISPLAY INVISIBLE (-250 4050);
FORCEPROP 2 LAST SEC 1
J 0
(-250 4050);
DISPLAY 0.680851 (-250 4050);
PAINT MONO (-250 4050);
DISPLAY INVISIBLE (-250 4050);
FORCEPROP 2 LAST ROOM DB1200ZL
J 0
(-250 4100);
DISPLAY 1.021277 (-250 4100);
PAINT ORANGE (-250 4100);
DISPLAY INVISIBLE (-250 4100);
FORCEPROP 2 LAST CDS_LOCATION EU4D2
J 0
(-250 4000);
DISPLAY 0.617021 (-250 4000);
PAINT AQUA (-250 4000);
DISPLAY INVISIBLE (-250 4000);
FORCEADD CAP..1
(1975 900);
FORCEPROP 1 LAST LOCATION C3D22
J 0
(2025 1000);
DISPLAY 0.617021 (2025 1000);
PAINT AQUA (2025 1000);
FORCEPROP 1 LAST PART_NUMBER G10601-001
J 0
(2025 750);
DISPLAY 0.617021 (2025 750);
PAINT BLUE (2025 750);
FORCEPROP 1 LAST VALUE 10UF
J 0
(2025 950);
DISPLAY 0.617021 (2025 950);
PAINT SKYBLUE (2025 950);
FORCEPROP 1 LAST TOLERANCE 10%
J 0
(2025 850);
DISPLAY 0.617021 (2025 850);
PAINT SKYBLUE (2025 850);
FORCEPROP 1 LAST PACK_TYPE 0805
J 0
(2025 700);
DISPLAY 0.617021 (2025 700);
PAINT SKYBLUE (2025 700);
FORCEPROP 1 LAST VOLTAGE 16V
J 0
(2025 900);
DISPLAY 0.617021 (2025 900);
PAINT SKYBLUE (2025 900);
FORCEPROP 1 LAST MATERIAL X7R
J 0
(2025 800);
DISPLAY 0.617021 (2025 800);
PAINT SKYBLUE (2025 800);
FORCEPROP 1 LASTPIN (1975 1000) $PN 1
J 0
(1985 980);
DISPLAY 0.617021 (1985 980);
PAINT ORANGE (1985 980);
FORCEPROP 1 LASTPIN (1975 800) $PN 2
J 0
(1985 780);
DISPLAY 0.617021 (1985 780);
PAINT ORANGE (1985 780);
FORCEPROP 2 LAST BOM_COST SYS_CLOCK
J 0
(2025 1200);
DISPLAY 1.021277 (2025 1200);
PAINT ORANGE (2025 1200);
DISPLAY INVISIBLE (2025 1200);
FORCEPROP 2 LAST SEC_TYPE 0805
J 0
(2025 1100);
DISPLAY 1.021277 (2025 1100);
PAINT ORANGE (2025 1100);
DISPLAY INVISIBLE (2025 1100);
FORCEPROP 2 LAST SEC 1
J 0
(2025 1100);
DISPLAY 0.680851 (2025 1100);
PAINT MONO (2025 1100);
DISPLAY INVISIBLE (2025 1100);
FORCEPROP 2 LAST CDS_LOCATION C3D22
J 0
(2025 1000);
DISPLAY 0.617021 (2025 1000);
PAINT AQUA (2025 1000);
DISPLAY INVISIBLE (2025 1000);
FORCEPROP 1 LAST PATH I10
J 0
(2025 1050);
DISPLAY 0.978723 (2025 1050);
PAINT WHITE (2025 1050);
DISPLAY INVISIBLE (2025 1050);
FORCEPROP 2 LAST ROOM DB1200ZL
J 0
(2025 1100);
DISPLAY 1.021277 (2025 1100);
PAINT ORANGE (2025 1100);
DISPLAY INVISIBLE (2025 1100);
FORCEPROP 2 LAST CDS_LIB mstr_discrete
J 0
(1975 900);
PAINT ORANGE (1975 900);
DISPLAY INVISIBLE (1975 900);
FORCEADD FET_N_DUAL..5
R 3
(2000 4100);
FORCEPROP 1 LASTPIN (2200 4100) $PN 4
J 0
(2150 4117);
DISPLAY 0.872340 (2150 4117);
PAINT WHITE (2150 4117);
FORCEPROP 1 LASTPIN (2100 4300) $PN 5
J 0
(2035 4272);
DISPLAY 0.872340 (2035 4272);
PAINT WHITE (2035 4272);
FORCEPROP 1 LASTPIN (1800 4100) $PN 3
J 0
(1810 4122);
DISPLAY 0.872340 (1810 4122);
PAINT WHITE (1810 4122);
FORCEPROP 1 LAST VALUE 2N7002DW
J 0
(2150 3950);
DISPLAY 0.617021 (2150 3950);
PAINT SKYBLUE (2150 3950);
FORCEPROP 1 LAST MATERIAL FET
J 0
(2150 3900);
DISPLAY 0.617021 (2150 3900);
PAINT SKYBLUE (2150 3900);
FORCEPROP 1 LAST PART_NUMBER D24280-001
J 0
(2150 3850);
DISPLAY 0.617021 (2150 3850);
PAINT BLUE (2150 3850);
FORCEPROP 1 LAST LOCATION Q4W1
J 0
(2150 4000);
DISPLAY 0.617021 (2150 4000);
PAINT AQUA (2150 4000);
FORCEPROP 0 LAST CDS_SEC 2
R 1
J 2
(1950 3900);
PAINT MONO (1950 3900);
DISPLAY INVISIBLE (1950 3900);
FORCEPROP 2 LAST BOM_COST DEBUG
R 1
J 2
(1900 3900);
DISPLAY 1.021277 (1900 3900);
PAINT ORANGE (1900 3900);
DISPLAY INVISIBLE (1900 3900);
FORCEPROP 2 LAST ROOM UART_MUX
R 1
J 2
(1950 3900);
DISPLAY 1.021277 (1950 3900);
PAINT ORANGE (1950 3900);
DISPLAY INVISIBLE (1950 3900);
FORCEPROP 2 LAST CDS_LIB mstr_discrete
R 1
J 2
(2000 4100);
PAINT MONO (2000 4100);
DISPLAY INVISIBLE (2000 4100);
FORCEPROP 1 LAST PACK_TYPE SMLF
R 1
J 2
(2150 3900);
DISPLAY 0.978723 (2150 3900);
PAINT SKYBLUE (2150 3900);
DISPLAY INVISIBLE (2150 3900);
FORCEPROP 0 LAST SEC 2
R 1
J 2
(1950 3900);
DISPLAY 0.680851 (1950 3900);
PAINT MONO (1950 3900);
DISPLAY INVISIBLE (1950 3900);
FORCEPROP 2 LAST SEC_TYPE SMLF
R 1
J 2
(1900 3900);
DISPLAY 1.021277 (1900 3900);
PAINT ORANGE (1900 3900);
DISPLAY INVISIBLE (1900 3900);
FORCEPROP 1 LAST PATH I101
R 1
J 2
(1950 3900);
DISPLAY 0.978723 (1950 3900);
PAINT BLUE (1950 3900);
DISPLAY INVISIBLE (1950 3900);
FORCEPROP 0 LAST CDS_LOCATION Q4W1
R 1
J 2
(1950 3900);
PAINT MONO (1950 3900);
DISPLAY INVISIBLE (1950 3900);
FORCEADD FET_N_DUAL..5
R 3
(2350 4500);
FORCEPROP 1 LAST PART_NUMBER D24280-001
J 0
(2500 4275);
DISPLAY 0.617021 (2500 4275);
PAINT BLUE (2500 4275);
FORCEPROP 1 LASTPIN (2550 4500) $PN 1
J 0
(2525 4517);
DISPLAY 0.872340 (2525 4517);
PAINT WHITE (2525 4517);
FORCEPROP 1 LASTPIN (2450 4700) $PN 2
J 0
(2385 4647);
DISPLAY 0.872340 (2385 4647);
PAINT WHITE (2385 4647);
FORCEPROP 1 LASTPIN (2150 4500) $PN 6
J 0
(2160 4522);
DISPLAY 0.872340 (2160 4522);
PAINT WHITE (2160 4522);
FORCEPROP 1 LAST MATERIAL FET
J 0
(2500 4325);
DISPLAY 0.617021 (2500 4325);
PAINT SKYBLUE (2500 4325);
FORCEPROP 1 LAST VALUE 2N7002DW
J 0
(2500 4375);
DISPLAY 0.617021 (2500 4375);
PAINT SKYBLUE (2500 4375);
FORCEPROP 1 LAST LOCATION Q4W1
J 0
(2500 4425);
DISPLAY 0.617021 (2500 4425);
PAINT AQUA (2500 4425);
FORCEPROP 2 LAST ROOM UART_MUX
R 1
J 2
(2300 4300);
DISPLAY 1.021277 (2300 4300);
PAINT ORANGE (2300 4300);
DISPLAY INVISIBLE (2300 4300);
FORCEPROP 2 LAST BOM_COST DEBUG
R 1
J 2
(2250 4300);
DISPLAY 1.021277 (2250 4300);
PAINT ORANGE (2250 4300);
DISPLAY INVISIBLE (2250 4300);
FORCEPROP 2 LAST CDS_LIB mstr_discrete
R 1
J 2
(2350 4500);
PAINT MONO (2350 4500);
DISPLAY INVISIBLE (2350 4500);
FORCEPROP 1 LAST PACK_TYPE SMLF
R 1
J 2
(2500 4300);
DISPLAY 0.978723 (2500 4300);
PAINT SKYBLUE (2500 4300);
DISPLAY INVISIBLE (2500 4300);
FORCEPROP 2 LAST SEC 1
R 1
J 2
(2250 4300);
DISPLAY 0.680851 (2250 4300);
PAINT MONO (2250 4300);
DISPLAY INVISIBLE (2250 4300);
FORCEPROP 2 LAST SEC_TYPE SMLF
R 1
J 2
(2250 4300);
DISPLAY 1.021277 (2250 4300);
PAINT ORANGE (2250 4300);
DISPLAY INVISIBLE (2250 4300);
FORCEPROP 0 LAST CDS_SEC 1
R 1
J 2
(2300 4300);
PAINT MONO (2300 4300);
DISPLAY INVISIBLE (2300 4300);
FORCEPROP 1 LAST PATH I102
R 1
J 2
(2300 4300);
DISPLAY 0.978723 (2300 4300);
PAINT BLUE (2300 4300);
DISPLAY INVISIBLE (2300 4300);
FORCEPROP 0 LAST CDS_LOCATION Q4W1
R 1
J 2
(2300 4300);
PAINT MONO (2300 4300);
DISPLAY INVISIBLE (2300 4300);
FORCEADD RES..2
(2450 4900);
FORCEPROP 1 LASTPIN (2450 4800) $PN 2
J 0
(2455 4810);
DISPLAY 0.617021 (2455 4810);
PAINT ORANGE (2455 4810);
FORCEPROP 1 LASTPIN (2450 5000) $PN 1
J 0
(2455 4962);
DISPLAY 0.617021 (2455 4962);
PAINT ORANGE (2455 4962);
FORCEPROP 1 LAST LOCATION R4W2
J 0
(2495 5025);
DISPLAY 0.617021 (2495 5025);
PAINT AQUA (2495 5025);
FORCEPROP 1 LAST VALUE 1.00K
J 0
(2495 4975);
DISPLAY 0.617021 (2495 4975);
PAINT SKYBLUE (2495 4975);
FORCEPROP 1 LAST PART_NUMBER G21796-026
J 0
(2490 4775);
DISPLAY 0.617021 (2490 4775);
PAINT BLUE (2490 4775);
FORCEPROP 1 LAST MATERIAL CHIP
J 0
(2490 4825);
DISPLAY 0.617021 (2490 4825);
PAINT SKYBLUE (2490 4825);
FORCEPROP 1 LAST WATTAGE 1/16W
J 0
(2490 4875);
DISPLAY 0.617021 (2490 4875);
PAINT SKYBLUE (2490 4875);
FORCEPROP 1 LAST PACK_TYPE 0402
J 0
(2490 4725);
DISPLAY 0.617021 (2490 4725);
PAINT SKYBLUE (2490 4725);
FORCEPROP 1 LAST TOLERANCE 1%
J 0
(2495 4925);
DISPLAY 0.617021 (2495 4925);
PAINT SKYBLUE (2495 4925);
FORCEPROP 2 LAST CDS_LIB mstr_discrete
J 0
(2450 4900);
PAINT MONO (2450 4900);
DISPLAY INVISIBLE (2450 4900);
FORCEPROP 2 LAST SEC 1
J 0
(2500 5125);
DISPLAY 0.680851 (2500 5125);
PAINT MONO (2500 5125);
DISPLAY INVISIBLE (2500 5125);
FORCEPROP 2 LAST SEC_TYPE 0402
J 0
(2500 5125);
DISPLAY 1.021277 (2500 5125);
PAINT ORANGE (2500 5125);
DISPLAY INVISIBLE (2500 5125);
FORCEPROP 0 LAST ROOM PROC_SIDEBAND
J 0
(2500 5125);
DISPLAY 1.021277 (2500 5125);
PAINT ORANGE (2500 5125);
DISPLAY INVISIBLE (2500 5125);
FORCEPROP 1 LAST PATH I103
J 0
(2500 5075);
DISPLAY 0.978723 (2500 5075);
PAINT WHITE (2500 5075);
DISPLAY INVISIBLE (2500 5075);
FORCEPROP 2 LAST CDS_LOCATION R4W2
J 0
(2495 5025);
DISPLAY 0.617021 (2495 5025);
PAINT AQUA (2495 5025);
DISPLAY INVISIBLE (2495 5025);
FORCEADD VCC_CORE..1
(2450 5100);
FORCEPROP 3 LASTPIN (2450 5050) SIG_NAME P3V3_DB1200\g
J 0
(2460 5060);
DISPLAY 0.659574 (2460 5060);
PAINT MONO (2460 5060);
DISPLAY INVISIBLE (2460 5060);
FORCEPROP 1 LAST HDL_POWER P3V3_DB1200
J 1
(2500 5150);
DISPLAY 0.617021 (2500 5150);
PAINT GREEN (2500 5150);
FORCEPROP 2 LAST CDS_LIB mstr_symbols
J 0
(2450 5100);
PAINT ORANGE (2450 5100);
DISPLAY INVISIBLE (2450 5100);
FORCEPROP 0 LAST VOLTAGE 5
J 0
(2450 5100);
PAINT SKYBLUE (2450 5100);
DISPLAY INVISIBLE (2450 5100);
FORCEPROP 1 LAST PATH I104
J 0
(2500 5125);
DISPLAY 0.872340 (2500 5125);
PAINT AQUA (2500 5125);
DISPLAY INVISIBLE (2500 5125);
FORCEADD RES..1
R 5
(3300 4750);
FORCEPROP 1 LASTPIN (3300 4850) $PN 1
J 0
(3312 4838);
DISPLAY 0.787234 (3312 4838);
PAINT ORANGE (3312 4838);
FORCEPROP 1 LAST TOLERANCE 5%
J 0
(3350 4800);
DISPLAY 0.638298 (3350 4800);
PAINT SKYBLUE (3350 4800);
FORCEPROP 1 LAST VALUE 3.3K
J 0
(3350 4850);
DISPLAY 0.638298 (3350 4850);
PAINT SKYBLUE (3350 4850);
FORCEPROP 1 LAST WATTAGE 1/16W
J 0
(3350 4750);
DISPLAY 0.638298 (3350 4750);
PAINT SKYBLUE (3350 4750);
FORCEPROP 1 LAST MATERIAL CHIP
J 0
(3350 4700);
DISPLAY 0.638298 (3350 4700);
PAINT SKYBLUE (3350 4700);
FORCEPROP 1 LAST LOCATION R4W3
J 0
(3350 4900);
DISPLAY 0.638298 (3350 4900);
PAINT SKYBLUE (3350 4900);
FORCEPROP 1 LASTPIN (3300 4650) $PN 2
J 0
(3312 4638);
DISPLAY 0.787234 (3312 4638);
PAINT ORANGE (3312 4638);
FORCEPROP 1 LAST PART_NUMBER G21497-013
J 0
(3350 4650);
DISPLAY 0.638298 (3350 4650);
PAINT BLUE (3350 4650);
FORCEPROP 1 LAST PACK_TYPE 0402
J 0
(3350 4600);
DISPLAY 0.638298 (3350 4600);
PAINT SKYBLUE (3350 4600);
FORCEPROP 1 LAST PATH I105
R 3
J 0
(3450 4800);
DISPLAY 0.978723 (3450 4800);
PAINT WHITE (3450 4800);
DISPLAY INVISIBLE (3450 4800);
FORCEPROP 2 LAST SEC 1
J 0
(3325 4875);
DISPLAY 0.680851 (3325 4875);
PAINT MONO (3325 4875);
DISPLAY INVISIBLE (3325 4875);
FORCEPROP 2 LAST SEC_TYPE 0402
J 0
(3325 4875);
DISPLAY 1.021277 (3325 4875);
PAINT ORANGE (3325 4875);
DISPLAY INVISIBLE (3325 4875);
FORCEPROP 2 LAST CDS_LIB mstr_discrete
R 3
J 0
(3300 4750);
PAINT MONO (3300 4750);
DISPLAY INVISIBLE (3300 4750);
FORCEADD RES..1
R 5
(3650 4750);
FORCEPROP 1 LASTPIN (3650 4850) $PN 1
J 0
(3662 4838);
DISPLAY 0.787234 (3662 4838);
PAINT ORANGE (3662 4838);
FORCEPROP 1 LAST TOLERANCE 5%
J 0
(3700 4800);
DISPLAY 0.638298 (3700 4800);
PAINT SKYBLUE (3700 4800);
FORCEPROP 1 LAST WATTAGE 1/16W
J 0
(3700 4750);
DISPLAY 0.638298 (3700 4750);
PAINT SKYBLUE (3700 4750);
FORCEPROP 1 LAST MATERIAL CHIP
J 0
(3700 4700);
DISPLAY 0.638298 (3700 4700);
PAINT SKYBLUE (3700 4700);
FORCEPROP 1 LASTPIN (3650 4650) $PN 2
J 0
(3662 4638);
DISPLAY 0.787234 (3662 4638);
PAINT ORANGE (3662 4638);
FORCEPROP 1 LAST VALUE 3.3K
J 0
(3700 4850);
DISPLAY 0.638298 (3700 4850);
PAINT SKYBLUE (3700 4850);
FORCEPROP 1 LAST LOCATION R4W4
J 0
(3700 4900);
DISPLAY 0.638298 (3700 4900);
PAINT SKYBLUE (3700 4900);
FORCEPROP 1 LAST PART_NUMBER G21497-013
J 0
(3700 4650);
DISPLAY 0.638298 (3700 4650);
PAINT BLUE (3700 4650);
FORCEPROP 1 LAST PACK_TYPE 0402
J 0
(3700 4600);
DISPLAY 0.638298 (3700 4600);
PAINT SKYBLUE (3700 4600);
FORCEPROP 1 LAST PATH I106
R 3
J 0
(3800 4800);
DISPLAY 0.978723 (3800 4800);
PAINT WHITE (3800 4800);
DISPLAY INVISIBLE (3800 4800);
FORCEPROP 2 LAST SEC 1
J 0
(3675 4875);
DISPLAY 0.680851 (3675 4875);
PAINT MONO (3675 4875);
DISPLAY INVISIBLE (3675 4875);
FORCEPROP 2 LAST SEC_TYPE 0402
J 0
(3675 4875);
DISPLAY 1.021277 (3675 4875);
PAINT ORANGE (3675 4875);
DISPLAY INVISIBLE (3675 4875);
FORCEPROP 2 LAST CDS_LIB mstr_discrete
R 3
J 0
(3650 4750);
PAINT MONO (3650 4750);
DISPLAY INVISIBLE (3650 4750);
FORCEADD VCC_CORE..1
(3650 5100);
FORCEPROP 3 LASTPIN (3650 5050) SIG_NAME P3V3_DB1200\g
J 0
(3660 5060);
DISPLAY 0.659574 (3660 5060);
PAINT MONO (3660 5060);
DISPLAY INVISIBLE (3660 5060);
FORCEPROP 1 LAST HDL_POWER P3V3_DB1200
J 1
(3700 5150);
DISPLAY 0.617021 (3700 5150);
PAINT GREEN (3700 5150);
FORCEPROP 0 LAST VOLTAGE 5
J 0
(3650 5100);
PAINT SKYBLUE (3650 5100);
DISPLAY INVISIBLE (3650 5100);
FORCEPROP 2 LAST CDS_LIB mstr_symbols
J 0
(3650 5100);
PAINT ORANGE (3650 5100);
DISPLAY INVISIBLE (3650 5100);
FORCEPROP 1 LAST PATH I107
J 0
(3700 5125);
DISPLAY 0.872340 (3700 5125);
PAINT AQUA (3700 5125);
DISPLAY INVISIBLE (3700 5125);
FORCEADD RES..2
(-2400 2350);
FORCEPROP 1 LASTPIN (-2400 2250) $PN 2
J 0
(-2395 2260);
DISPLAY 0.617021 (-2395 2260);
PAINT ORANGE (-2395 2260);
FORCEPROP 1 LASTPIN (-2400 2450) $PN 1
J 0
(-2395 2412);
DISPLAY 0.617021 (-2395 2412);
PAINT ORANGE (-2395 2412);
FORCEPROP 1 LAST VALUE 4.75K
J 0
(-2355 2425);
DISPLAY 0.617021 (-2355 2425);
PAINT SKYBLUE (-2355 2425);
FORCEPROP 1 LAST TOLERANCE 1%
J 0
(-2355 2375);
DISPLAY 0.617021 (-2355 2375);
PAINT SKYBLUE (-2355 2375);
FORCEPROP 1 LAST WATTAGE 1/16W
J 0
(-2360 2325);
DISPLAY 0.617021 (-2360 2325);
PAINT SKYBLUE (-2360 2325);
FORCEPROP 1 LAST LOCATION R4W6
J 0
(-2355 2475);
DISPLAY 0.617021 (-2355 2475);
PAINT AQUA (-2355 2475);
FORCEPROP 1 LAST PACK_TYPE 0402
J 0
(-2210 2375);
DISPLAY 0.617021 (-2210 2375);
PAINT SKYBLUE (-2210 2375);
FORCEPROP 1 LAST PART_NUMBER G21796-072
J 0
(-2210 2425);
DISPLAY 0.617021 (-2210 2425);
PAINT BLUE (-2210 2425);
FORCEPROP 1 LAST MATERIAL CHIP
J 0
(-2210 2475);
DISPLAY 0.617021 (-2210 2475);
PAINT SKYBLUE (-2210 2475);
FORCEPROP 1 LAST PATH I109
J 0
(-2350 2525);
DISPLAY 0.978723 (-2350 2525);
PAINT WHITE (-2350 2525);
DISPLAY INVISIBLE (-2350 2525);
FORCEPROP 2 LAST CDS_LIB mstr_discrete
J 0
(-2400 2350);
PAINT ORANGE (-2400 2350);
DISPLAY INVISIBLE (-2400 2350);
FORCEPROP 2 LAST ROOM DB1200ZL
J 0
(-2350 2575);
DISPLAY 1.021277 (-2350 2575);
PAINT ORANGE (-2350 2575);
DISPLAY INVISIBLE (-2350 2575);
FORCEPROP 2 LAST SEC 1
J 0
(-2350 2575);
DISPLAY 0.680851 (-2350 2575);
PAINT MONO (-2350 2575);
DISPLAY INVISIBLE (-2350 2575);
FORCEPROP 2 LAST BOM_COST SYS_CLOCK
J 0
(-2350 2675);
DISPLAY 1.021277 (-2350 2675);
PAINT ORANGE (-2350 2675);
DISPLAY INVISIBLE (-2350 2675);
FORCEPROP 2 LAST SEC_TYPE 0402
J 0
(-2350 2575);
DISPLAY 1.021277 (-2350 2575);
PAINT ORANGE (-2350 2575);
DISPLAY INVISIBLE (-2350 2575);
FORCEPROP 2 LAST CDS_LOCATION R4W6
J 0
(-2355 2475);
DISPLAY 0.617021 (-2355 2475);
PAINT AQUA (-2355 2475);
DISPLAY INVISIBLE (-2355 2475);
FORCEADD CAP_A..1
(2575 900);
FORCEPROP 1 LAST LOCATION C6P4
J 0
(2625 1000);
DISPLAY 0.617021 (2625 1000);
PAINT AQUA (2625 1000);
FORCEPROP 1 LASTPIN (2575 1000) $PN 1
J 0
(2585 980);
DISPLAY 0.617021 (2585 980);
PAINT ORANGE (2585 980);
FORCEPROP 1 LAST PART_NUMBER A36096-030
J 0
(2625 750);
DISPLAY 0.617021 (2625 750);
PAINT BLUE (2625 750);
FORCEPROP 1 LASTPIN (2575 800) $PN 2
J 0
(2585 780);
DISPLAY 0.617021 (2585 780);
PAINT ORANGE (2585 780);
FORCEPROP 1 LAST MATERIAL X7R
J 0
(2625 800);
DISPLAY 0.617021 (2625 800);
PAINT SKYBLUE (2625 800);
FORCEPROP 1 LAST PACK_TYPE 0402V
J 0
(2625 700);
DISPLAY 0.617021 (2625 700);
PAINT SKYBLUE (2625 700);
FORCEPROP 1 LAST TOLERANCE 10%
J 0
(2625 850);
DISPLAY 0.617021 (2625 850);
PAINT SKYBLUE (2625 850);
FORCEPROP 1 LAST VOLTAGE 16V
J 0
(2625 900);
DISPLAY 0.617021 (2625 900);
PAINT SKYBLUE (2625 900);
FORCEPROP 1 LAST VALUE 0.1UF
J 0
(2625 950);
DISPLAY 0.617021 (2625 950);
PAINT SKYBLUE (2625 950);
FORCEPROP 2 LAST BOM_COST SYS_CLOCK
J 0
(2625 1200);
DISPLAY 1.021277 (2625 1200);
PAINT ORANGE (2625 1200);
DISPLAY INVISIBLE (2625 1200);
FORCEPROP 2 LAST SEC 1
J 0
(2625 1100);
DISPLAY 0.680851 (2625 1100);
PAINT MONO (2625 1100);
DISPLAY INVISIBLE (2625 1100);
FORCEPROP 2 LAST SEC_TYPE 0402V
J 0
(2625 1100);
DISPLAY 1.021277 (2625 1100);
PAINT ORANGE (2625 1100);
DISPLAY INVISIBLE (2625 1100);
FORCEPROP 2 LAST ROOM DB1200ZL
J 0
(2625 1100);
DISPLAY 1.021277 (2625 1100);
PAINT ORANGE (2625 1100);
DISPLAY INVISIBLE (2625 1100);
FORCEPROP 2 LAST CDS_SEC 1
J 0
(2625 1050);
PAINT ORANGE (2625 1050);
DISPLAY INVISIBLE (2625 1050);
FORCEPROP 1 LAST PATH I11
J 0
(2625 1050);
DISPLAY 0.978723 (2625 1050);
PAINT WHITE (2625 1050);
DISPLAY INVISIBLE (2625 1050);
FORCEPROP 2 LAST CDS_LOCATION C6P4
J 0
(2625 1000);
DISPLAY 0.617021 (2625 1000);
PAINT AQUA (2625 1000);
DISPLAY INVISIBLE (2625 1000);
FORCEPROP 2 LAST CDS_LIB dev_discrete
J 0
(2575 900);
PAINT ORANGE (2575 900);
DISPLAY INVISIBLE (2575 900);
FORCEADD VCC_CORE..1
(-2400 2550);
FORCEPROP 3 LASTPIN (-2400 2500) SIG_NAME P3V3_DB1200\g
J 0
(-2390 2510);
DISPLAY 0.659574 (-2390 2510);
PAINT MONO (-2390 2510);
DISPLAY INVISIBLE (-2390 2510);
FORCEPROP 1 LAST HDL_POWER P3V3_DB1200
J 1
(-2350 2600);
DISPLAY 0.617021 (-2350 2600);
PAINT GREEN (-2350 2600);
FORCEPROP 1 LAST PATH I110
J 0
(-2350 2575);
DISPLAY 0.872340 (-2350 2575);
PAINT AQUA (-2350 2575);
DISPLAY INVISIBLE (-2350 2575);
FORCEPROP 0 LAST VOLTAGE 5
J 0
(-2400 2550);
PAINT SKYBLUE (-2400 2550);
DISPLAY INVISIBLE (-2400 2550);
FORCEPROP 2 LAST CDS_LIB mstr_symbols
J 0
(-2400 2550);
PAINT ORANGE (-2400 2550);
DISPLAY INVISIBLE (-2400 2550);
FORCEADD OFFPAGE..1
(-2350 1850);
FORCEPROP 2 LAST $XR0 191 
J 0
(-2602 1850);
DISPLAY 0.638298 (-2602 1850);
PAINT MONO (-2602 1850);
FORCEPROP 2 LAST CDS_LIB mstr_standard
J 0
(-2350 1850);
PAINT ORANGE (-2350 1850);
DISPLAY INVISIBLE (-2350 1850);
FORCEPROP 2 LAST PATH I111
J 0
(-2600 1900);
DISPLAY 1.021277 (-2600 1900);
PAINT ORANGE (-2600 1900);
DISPLAY INVISIBLE (-2600 1900);
FORCEPROP 1 LAST OFFPAGE TRUE
J 0
(-2025 1725);
PAINT GREEN (-2025 1725);
DISPLAY INVISIBLE (-2025 1725);
FORCEPROP 1 LAST COMMENT_BODY TRUE
J 0
(-2225 1750);
DISPLAY 1.404255 (-2225 1750);
PAINT PEACH (-2225 1750);
DISPLAY INVISIBLE (-2225 1750);
FORCEADD FET_N..8
(-950 1950);
FORCEPROP 1 LAST VALUE 2N7002
J 0
(-750 1900);
DISPLAY 0.617021 (-750 1900);
PAINT SKYBLUE (-750 1900);
FORCEPROP 1 LAST PART_NUMBER C79254-001
J 0
(-750 1750);
DISPLAY 0.617021 (-750 1750);
PAINT BLUE (-750 1750);
FORCEPROP 1 LASTPIN (-950 1750) $PN 2
J 2
(-892 1750);
DISPLAY 0.617021 (-892 1750);
PAINT WHITE (-892 1750);
FORCEPROP 1 LASTPIN (-950 2150) $PN 3
J 2
(-897 2115);
DISPLAY 0.617021 (-897 2115);
PAINT WHITE (-897 2115);
FORCEPROP 1 LASTPIN (-1150 1850) $PN 1
J 2
(-1147 1865);
DISPLAY 0.617021 (-1147 1865);
PAINT WHITE (-1147 1865);
FORCEPROP 1 LAST LOCATION Q4W2
J 0
(-750 1950);
DISPLAY 0.617021 (-750 1950);
PAINT AQUA (-750 1950);
FORCEPROP 1 LAST MATERIAL FET
J 0
(-750 1850);
DISPLAY 0.617021 (-750 1850);
PAINT SKYBLUE (-750 1850);
FORCEPROP 1 LAST PACK_TYPE SOT23LF
J 0
(-750 1800);
DISPLAY 0.978723 (-750 1800);
PAINT SKYBLUE (-750 1800);
DISPLAY INVISIBLE (-750 1800);
FORCEPROP 0 LAST ROOM HOT_SWAP
J 0
(-750 2050);
DISPLAY 1.021277 (-750 2050);
PAINT ORANGE (-750 2050);
DISPLAY INVISIBLE (-750 2050);
FORCEPROP 2 LAST SEC_TYPE SOT23LF
J 0
(-750 2050);
DISPLAY 1.021277 (-750 2050);
PAINT ORANGE (-750 2050);
DISPLAY INVISIBLE (-750 2050);
FORCEPROP 2 LAST SEC 1
J 0
(-750 2050);
DISPLAY 0.680851 (-750 2050);
PAINT MONO (-750 2050);
DISPLAY INVISIBLE (-750 2050);
FORCEPROP 2 LAST CDS_LIB mstr_discrete
J 0
(-950 1950);
PAINT ORANGE (-950 1950);
DISPLAY INVISIBLE (-950 1950);
FORCEPROP 1 LAST PATH I112
J 0
(-750 2000);
DISPLAY 0.978723 (-750 2000);
PAINT BLUE (-750 2000);
DISPLAY INVISIBLE (-750 2000);
FORCEPROP 2 LAST CDS_LOCATION Q4W2
J 0
(-750 1950);
DISPLAY 0.617021 (-750 1950);
PAINT AQUA (-750 1950);
DISPLAY INVISIBLE (-750 1950);
FORCEADD GND..1
(-950 1650);
FORCEPROP 3 LASTPIN (-950 1700) SIG_NAME GND\g
J 0
(-940 1710);
DISPLAY 0.659574 (-940 1710);
PAINT MONO (-940 1710);
DISPLAY INVISIBLE (-940 1710);
FORCEPROP 2 LAST ROOM DB1200ZL
J 0
(-1275 1725);
DISPLAY 1.127660 (-1275 1725);
PAINT WHITE (-1275 1725);
DISPLAY INVISIBLE (-1275 1725);
FORCEPROP 2 LAST BOM_COST SYS_CLOCK
J 0
(-1400 1725);
DISPLAY 1.617021 (-1400 1725);
PAINT WHITE (-1400 1725);
DISPLAY INVISIBLE (-1400 1725);
FORCEPROP 1 LAST VOLTAGE 0.0V
J 0
(-995 1607);
DISPLAY 0.340426 (-995 1607);
PAINT SKYBLUE (-995 1607);
DISPLAY INVISIBLE (-995 1607);
FORCEPROP 2 LAST CDS_LIB mstr_symbols
J 0
(-950 1650);
PAINT ORANGE (-950 1650);
DISPLAY INVISIBLE (-950 1650);
FORCEPROP 1 LAST SIZE 1B
J 0
(-875 1600);
DISPLAY 1.127660 (-875 1600);
PAINT ORANGE (-875 1600);
DISPLAY INVISIBLE (-875 1600);
FORCEPROP 1 LAST PATH I113
J 0
(-875 1650);
DISPLAY 0.872340 (-875 1650);
PAINT AQUA (-875 1650);
DISPLAY INVISIBLE (-875 1650);
FORCEPROP 1 LAST BODY_TYPE PLUMBING
J 0
(-995 1607);
DISPLAY 0.340426 (-995 1607);
PAINT GREEN (-995 1607);
DISPLAY INVISIBLE (-995 1607);
FORCEPROP 1 LAST HDL_POWER GND
J 0
(-950 1800);
PAINT GREEN (-950 1800);
DISPLAY INVISIBLE (-950 1800);
FORCEADD RES..1
R 1
(-1650 2000);
FORCEPROP 1 LAST LOCATION R4W5
J 0
(-1600 2075);
DISPLAY 0.617021 (-1600 2075);
PAINT AQUA (-1600 2075);
FORCEPROP 1 LAST TOLERANCE 5%
J 0
(-1600 1975);
DISPLAY 0.617021 (-1600 1975);
PAINT SKYBLUE (-1600 1975);
FORCEPROP 1 LASTPIN (-1650 2100) $PN 2
R 1
J 0
(-1662 2062);
DISPLAY 0.787234 (-1662 2062);
PAINT ORANGE (-1662 2062);
FORCEPROP 1 LAST VALUE 0.0
J 0
(-1600 2025);
DISPLAY 0.617021 (-1600 2025);
PAINT SKYBLUE (-1600 2025);
FORCEPROP 1 LAST PART_NUMBER G21497-005
J 0
(-1450 2025);
DISPLAY 0.617021 (-1450 2025);
PAINT BLUE (-1450 2025);
FORCEPROP 1 LAST MATERIAL EMPTY
J 0
(-1450 2075);
DISPLAY 0.617021 (-1450 2075);
PAINT RED (-1450 2075);
FORCEPROP 1 LASTPIN (-1650 1900) $PN 1
R 1
J 0
(-1662 1912);
DISPLAY 0.787234 (-1662 1912);
PAINT ORANGE (-1662 1912);
FORCEPROP 1 LAST WATTAGE 1/16W
J 0
(-1600 1925);
DISPLAY 0.617021 (-1600 1925);
PAINT SKYBLUE (-1600 1925);
FORCEPROP 1 LAST PACK_TYPE 0402
J 0
(-1450 1975);
DISPLAY 0.617021 (-1450 1975);
PAINT SKYBLUE (-1450 1975);
FORCEPROP 2 LAST SEC 1
R 1
J 0
(-1850 1950);
PAINT MONO (-1850 1950);
DISPLAY INVISIBLE (-1850 1950);
FORCEPROP 2 LAST SEC_TYPE 0402
R 1
J 0
(-1850 1950);
DISPLAY 1.021277 (-1850 1950);
PAINT ORANGE (-1850 1950);
DISPLAY INVISIBLE (-1850 1950);
FORCEPROP 0 LAST BOM_COST MEM_NV
R 1
J 0
(-1950 1950);
DISPLAY 1.021277 (-1950 1950);
PAINT ORANGE (-1950 1950);
DISPLAY INVISIBLE (-1950 1950);
FORCEPROP 0 LAST ROOM NV_DIMM
R 1
J 0
(-1850 1950);
DISPLAY 1.021277 (-1850 1950);
PAINT ORANGE (-1850 1950);
DISPLAY INVISIBLE (-1850 1950);
FORCEPROP 2 LAST CDS_LIB mstr_discrete
R 1
J 0
(-1650 2000);
PAINT MONO (-1650 2000);
DISPLAY INVISIBLE (-1650 2000);
FORCEPROP 1 LAST PATH I114
R 1
J 0
(-1800 1950);
DISPLAY 0.978723 (-1800 1950);
PAINT WHITE (-1800 1950);
DISPLAY INVISIBLE (-1800 1950);
FORCEPROP 2 LAST CDS_LOCATION R4W5
R 1
J 0
(-1700 1950);
DISPLAY 0.617021 (-1700 1950);
PAINT AQUA (-1700 1950);
DISPLAY INVISIBLE (-1700 1950);
FORCEADD RES..2
(-750 1075);
FORCEPROP 1 LAST TOLERANCE 1%
J 0
(-705 1100);
DISPLAY 0.617021 (-705 1100);
PAINT SKYBLUE (-705 1100);
FORCEPROP 1 LAST PACK_TYPE 0402
J 0
(-710 900);
DISPLAY 0.617021 (-710 900);
PAINT SKYBLUE (-710 900);
FORCEPROP 1 LASTPIN (-750 1175) $PN 1
J 0
(-745 1137);
DISPLAY 0.617021 (-745 1137);
PAINT ORANGE (-745 1137);
FORCEPROP 1 LASTPIN (-750 975) $PN 2
J 0
(-745 985);
DISPLAY 0.617021 (-745 985);
PAINT ORANGE (-745 985);
FORCEPROP 1 LAST LOCATION R6P48
J 0
(-705 1200);
DISPLAY 0.617021 (-705 1200);
PAINT AQUA (-705 1200);
FORCEPROP 1 LAST VALUE 1.00K
J 0
(-705 1150);
DISPLAY 0.617021 (-705 1150);
PAINT SKYBLUE (-705 1150);
FORCEPROP 1 LAST PART_NUMBER G21796-026
J 0
(-710 950);
DISPLAY 0.617021 (-710 950);
PAINT BLUE (-710 950);
FORCEPROP 1 LAST MATERIAL CHIP
J 0
(-710 1000);
DISPLAY 0.617021 (-710 1000);
PAINT SKYBLUE (-710 1000);
FORCEPROP 1 LAST WATTAGE 1/16W
J 0
(-710 1050);
DISPLAY 0.617021 (-710 1050);
PAINT SKYBLUE (-710 1050);
FORCEPROP 1 LAST PATH I115
J 0
(-700 1250);
DISPLAY 0.978723 (-700 1250);
PAINT WHITE (-700 1250);
DISPLAY INVISIBLE (-700 1250);
FORCEPROP 2 LAST CDS_LIB mstr_discrete
J 0
(-750 1075);
PAINT MONO (-750 1075);
DISPLAY INVISIBLE (-750 1075);
FORCEPROP 2 LAST SEC 1
J 0
(-700 1300);
DISPLAY 0.680851 (-700 1300);
PAINT MONO (-700 1300);
DISPLAY INVISIBLE (-700 1300);
FORCEPROP 2 LAST SEC_TYPE 0402
J 0
(-700 1300);
DISPLAY 1.021277 (-700 1300);
PAINT ORANGE (-700 1300);
DISPLAY INVISIBLE (-700 1300);
FORCEPROP 0 LAST ROOM PROC_SIDEBAND
J 0
(-700 1300);
DISPLAY 1.021277 (-700 1300);
PAINT ORANGE (-700 1300);
DISPLAY INVISIBLE (-700 1300);
FORCEPROP 2 LAST CDS_LOCATION R6P48
J 0
(-705 1200);
DISPLAY 0.617021 (-705 1200);
PAINT AQUA (-705 1200);
DISPLAY INVISIBLE (-705 1200);
FORCEADD CAP_A..1
(2825 900);
FORCEPROP 1 LAST PART_NUMBER A36096-030
J 0
(2875 750);
DISPLAY 0.617021 (2875 750);
PAINT BLUE (2875 750);
FORCEPROP 1 LAST LOCATION C6P6
J 0
(2875 1000);
DISPLAY 0.617021 (2875 1000);
PAINT AQUA (2875 1000);
FORCEPROP 1 LASTPIN (2825 1000) $PN 1
J 0
(2835 980);
DISPLAY 0.617021 (2835 980);
PAINT ORANGE (2835 980);
FORCEPROP 1 LASTPIN (2825 800) $PN 2
J 0
(2835 780);
DISPLAY 0.617021 (2835 780);
PAINT ORANGE (2835 780);
FORCEPROP 1 LAST MATERIAL X7R
J 0
(2875 800);
DISPLAY 0.617021 (2875 800);
PAINT SKYBLUE (2875 800);
FORCEPROP 1 LAST VOLTAGE 16V
J 0
(2875 900);
DISPLAY 0.617021 (2875 900);
PAINT SKYBLUE (2875 900);
FORCEPROP 1 LAST PACK_TYPE 0402V
J 0
(2875 700);
DISPLAY 0.617021 (2875 700);
PAINT SKYBLUE (2875 700);
FORCEPROP 1 LAST TOLERANCE 10%
J 0
(2875 850);
DISPLAY 0.617021 (2875 850);
PAINT SKYBLUE (2875 850);
FORCEPROP 1 LAST VALUE 0.1UF
J 0
(2875 950);
DISPLAY 0.617021 (2875 950);
PAINT SKYBLUE (2875 950);
FORCEPROP 2 LAST BOM_COST SYS_CLOCK
J 0
(2875 1200);
DISPLAY 1.021277 (2875 1200);
PAINT ORANGE (2875 1200);
DISPLAY INVISIBLE (2875 1200);
FORCEPROP 1 LAST PATH I12
J 0
(2875 1050);
DISPLAY 0.978723 (2875 1050);
PAINT WHITE (2875 1050);
DISPLAY INVISIBLE (2875 1050);
FORCEPROP 2 LAST ROOM DB1200ZL
J 0
(2875 1100);
DISPLAY 1.021277 (2875 1100);
PAINT ORANGE (2875 1100);
DISPLAY INVISIBLE (2875 1100);
FORCEPROP 2 LAST CDS_LOCATION C6P6
J 0
(2875 1000);
DISPLAY 0.617021 (2875 1000);
PAINT AQUA (2875 1000);
DISPLAY INVISIBLE (2875 1000);
FORCEPROP 2 LAST CDS_SEC 1
J 0
(2875 1050);
PAINT ORANGE (2875 1050);
DISPLAY INVISIBLE (2875 1050);
FORCEPROP 2 LAST SEC_TYPE 0402V
J 0
(2875 1100);
DISPLAY 1.021277 (2875 1100);
PAINT ORANGE (2875 1100);
DISPLAY INVISIBLE (2875 1100);
FORCEPROP 2 LAST SEC 1
J 0
(2875 1100);
DISPLAY 0.680851 (2875 1100);
PAINT MONO (2875 1100);
DISPLAY INVISIBLE (2875 1100);
FORCEPROP 2 LAST CDS_LIB dev_discrete
J 0
(2825 900);
PAINT ORANGE (2825 900);
DISPLAY INVISIBLE (2825 900);
FORCEADD CAP_A..1
(3050 900);
FORCEPROP 1 LAST LOCATION C6P10
J 0
(3100 1000);
DISPLAY 0.617021 (3100 1000);
PAINT AQUA (3100 1000);
FORCEPROP 1 LAST PART_NUMBER A36096-030
J 0
(3100 750);
DISPLAY 0.617021 (3100 750);
PAINT BLUE (3100 750);
FORCEPROP 1 LAST MATERIAL X7R
J 0
(3100 800);
DISPLAY 0.617021 (3100 800);
PAINT SKYBLUE (3100 800);
FORCEPROP 1 LAST VOLTAGE 16V
J 0
(3100 900);
DISPLAY 0.617021 (3100 900);
PAINT SKYBLUE (3100 900);
FORCEPROP 1 LAST PACK_TYPE 0402V
J 0
(3100 700);
DISPLAY 0.617021 (3100 700);
PAINT SKYBLUE (3100 700);
FORCEPROP 1 LAST TOLERANCE 10%
J 0
(3100 850);
DISPLAY 0.617021 (3100 850);
PAINT SKYBLUE (3100 850);
FORCEPROP 1 LASTPIN (3050 1000) $PN 1
J 0
(3060 980);
DISPLAY 0.617021 (3060 980);
PAINT ORANGE (3060 980);
FORCEPROP 1 LASTPIN (3050 800) $PN 2
J 0
(3060 780);
DISPLAY 0.617021 (3060 780);
PAINT ORANGE (3060 780);
FORCEPROP 1 LAST VALUE 0.1UF
J 0
(3100 950);
DISPLAY 0.617021 (3100 950);
PAINT SKYBLUE (3100 950);
FORCEPROP 2 LAST BOM_COST SYS_CLOCK
J 0
(3100 1200);
DISPLAY 1.021277 (3100 1200);
PAINT ORANGE (3100 1200);
DISPLAY INVISIBLE (3100 1200);
FORCEPROP 2 LAST SEC_TYPE 0402V
J 0
(3100 1100);
DISPLAY 1.021277 (3100 1100);
PAINT ORANGE (3100 1100);
DISPLAY INVISIBLE (3100 1100);
FORCEPROP 1 LAST PATH I13
J 0
(3100 1050);
DISPLAY 0.978723 (3100 1050);
PAINT WHITE (3100 1050);
DISPLAY INVISIBLE (3100 1050);
FORCEPROP 2 LAST ROOM DB1200ZL
J 0
(3100 1100);
DISPLAY 1.021277 (3100 1100);
PAINT ORANGE (3100 1100);
DISPLAY INVISIBLE (3100 1100);
FORCEPROP 2 LAST CDS_LOCATION C6P10
J 0
(3100 1000);
DISPLAY 0.617021 (3100 1000);
PAINT AQUA (3100 1000);
DISPLAY INVISIBLE (3100 1000);
FORCEPROP 2 LAST CDS_SEC 1
J 0
(3100 1050);
PAINT ORANGE (3100 1050);
DISPLAY INVISIBLE (3100 1050);
FORCEPROP 2 LAST SEC 1
J 0
(3100 1100);
DISPLAY 0.680851 (3100 1100);
PAINT MONO (3100 1100);
DISPLAY INVISIBLE (3100 1100);
FORCEPROP 2 LAST CDS_LIB dev_discrete
J 0
(3050 900);
PAINT ORANGE (3050 900);
DISPLAY INVISIBLE (3050 900);
FORCEADD CAP_A..1
(3275 900);
FORCEPROP 1 LASTPIN (3275 1000) $PN 1
J 0
(3285 980);
DISPLAY 0.617021 (3285 980);
PAINT ORANGE (3285 980);
FORCEPROP 1 LAST PACK_TYPE 0402V
J 0
(3325 700);
DISPLAY 0.617021 (3325 700);
PAINT SKYBLUE (3325 700);
FORCEPROP 1 LAST VOLTAGE 16V
J 0
(3325 900);
DISPLAY 0.617021 (3325 900);
PAINT SKYBLUE (3325 900);
FORCEPROP 1 LAST MATERIAL X7R
J 0
(3325 800);
DISPLAY 0.617021 (3325 800);
PAINT SKYBLUE (3325 800);
FORCEPROP 1 LASTPIN (3275 800) $PN 2
J 0
(3285 780);
DISPLAY 0.617021 (3285 780);
PAINT ORANGE (3285 780);
FORCEPROP 1 LAST TOLERANCE 10%
J 0
(3325 850);
DISPLAY 0.617021 (3325 850);
PAINT SKYBLUE (3325 850);
FORCEPROP 1 LAST PART_NUMBER A36096-030
J 0
(3325 750);
DISPLAY 0.617021 (3325 750);
PAINT BLUE (3325 750);
FORCEPROP 1 LAST VALUE 0.1UF
J 0
(3325 950);
DISPLAY 0.617021 (3325 950);
PAINT SKYBLUE (3325 950);
FORCEPROP 1 LAST LOCATION C6P5
J 0
(3325 1000);
DISPLAY 0.617021 (3325 1000);
PAINT AQUA (3325 1000);
FORCEPROP 2 LAST BOM_COST SYS_CLOCK
J 0
(3325 1200);
DISPLAY 1.021277 (3325 1200);
PAINT ORANGE (3325 1200);
DISPLAY INVISIBLE (3325 1200);
FORCEPROP 2 LAST SEC 1
J 0
(3325 1100);
DISPLAY 0.680851 (3325 1100);
PAINT MONO (3325 1100);
DISPLAY INVISIBLE (3325 1100);
FORCEPROP 2 LAST SEC_TYPE 0402V
J 0
(3325 1100);
DISPLAY 1.021277 (3325 1100);
PAINT ORANGE (3325 1100);
DISPLAY INVISIBLE (3325 1100);
FORCEPROP 2 LAST ROOM DB1200ZL
J 0
(3325 1100);
DISPLAY 1.021277 (3325 1100);
PAINT ORANGE (3325 1100);
DISPLAY INVISIBLE (3325 1100);
FORCEPROP 2 LAST CDS_SEC 1
J 0
(3325 1050);
PAINT ORANGE (3325 1050);
DISPLAY INVISIBLE (3325 1050);
FORCEPROP 1 LAST PATH I14
J 0
(3325 1050);
DISPLAY 0.978723 (3325 1050);
PAINT WHITE (3325 1050);
DISPLAY INVISIBLE (3325 1050);
FORCEPROP 2 LAST CDS_LOCATION C6P5
J 0
(3325 1000);
DISPLAY 0.617021 (3325 1000);
PAINT AQUA (3325 1000);
DISPLAY INVISIBLE (3325 1000);
FORCEPROP 2 LAST CDS_LIB dev_discrete
J 0
(3275 900);
PAINT ORANGE (3275 900);
DISPLAY INVISIBLE (3275 900);
FORCEADD CAP_A..1
(3475 900);
FORCEPROP 1 LAST VALUE 0.1UF
J 0
(3525 950);
DISPLAY 0.617021 (3525 950);
PAINT SKYBLUE (3525 950);
FORCEPROP 1 LASTPIN (3475 1000) $PN 1
J 0
(3485 980);
DISPLAY 0.617021 (3485 980);
PAINT ORANGE (3485 980);
FORCEPROP 1 LAST PART_NUMBER A36096-030
J 0
(3525 750);
DISPLAY 0.617021 (3525 750);
PAINT BLUE (3525 750);
FORCEPROP 1 LAST TOLERANCE 10%
J 0
(3525 850);
DISPLAY 0.617021 (3525 850);
PAINT SKYBLUE (3525 850);
FORCEPROP 1 LAST PACK_TYPE 0402V
J 0
(3525 700);
DISPLAY 0.617021 (3525 700);
PAINT SKYBLUE (3525 700);
FORCEPROP 1 LAST VOLTAGE 16V
J 0
(3525 900);
DISPLAY 0.617021 (3525 900);
PAINT SKYBLUE (3525 900);
FORCEPROP 1 LAST MATERIAL X7R
J 0
(3525 800);
DISPLAY 0.617021 (3525 800);
PAINT SKYBLUE (3525 800);
FORCEPROP 1 LASTPIN (3475 800) $PN 2
J 0
(3485 780);
DISPLAY 0.617021 (3485 780);
PAINT ORANGE (3485 780);
FORCEPROP 1 LAST LOCATION C6P12
J 0
(3525 1000);
DISPLAY 0.617021 (3525 1000);
PAINT AQUA (3525 1000);
FORCEPROP 2 LAST BOM_COST SYS_CLOCK
J 0
(3525 1200);
DISPLAY 1.021277 (3525 1200);
PAINT ORANGE (3525 1200);
DISPLAY INVISIBLE (3525 1200);
FORCEPROP 2 LAST SEC 1
J 0
(3525 1100);
DISPLAY 0.680851 (3525 1100);
PAINT MONO (3525 1100);
DISPLAY INVISIBLE (3525 1100);
FORCEPROP 2 LAST SEC_TYPE 0402V
J 0
(3525 1100);
DISPLAY 1.021277 (3525 1100);
PAINT ORANGE (3525 1100);
DISPLAY INVISIBLE (3525 1100);
FORCEPROP 2 LAST ROOM DB1200ZL
J 0
(3525 1100);
DISPLAY 1.021277 (3525 1100);
PAINT ORANGE (3525 1100);
DISPLAY INVISIBLE (3525 1100);
FORCEPROP 2 LAST CDS_SEC 1
J 0
(3525 1050);
PAINT ORANGE (3525 1050);
DISPLAY INVISIBLE (3525 1050);
FORCEPROP 1 LAST PATH I15
J 0
(3525 1050);
DISPLAY 0.978723 (3525 1050);
PAINT WHITE (3525 1050);
DISPLAY INVISIBLE (3525 1050);
FORCEPROP 2 LAST CDS_LOCATION C6P12
J 0
(3525 1000);
DISPLAY 0.617021 (3525 1000);
PAINT AQUA (3525 1000);
DISPLAY INVISIBLE (3525 1000);
FORCEPROP 2 LAST CDS_LIB dev_discrete
J 0
(3475 900);
PAINT ORANGE (3475 900);
DISPLAY INVISIBLE (3475 900);
FORCEADD CAP_A..1
(3700 900);
FORCEPROP 1 LAST LOCATION C6P11
J 0
(3750 1000);
DISPLAY 0.617021 (3750 1000);
PAINT AQUA (3750 1000);
FORCEPROP 1 LAST PART_NUMBER A36096-030
J 0
(3750 750);
DISPLAY 0.617021 (3750 750);
PAINT BLUE (3750 750);
FORCEPROP 1 LAST PACK_TYPE 0402V
J 0
(3750 700);
DISPLAY 0.617021 (3750 700);
PAINT SKYBLUE (3750 700);
FORCEPROP 1 LAST TOLERANCE 10%
J 0
(3750 850);
DISPLAY 0.617021 (3750 850);
PAINT SKYBLUE (3750 850);
FORCEPROP 1 LAST MATERIAL X7R
J 0
(3750 800);
DISPLAY 0.617021 (3750 800);
PAINT SKYBLUE (3750 800);
FORCEPROP 1 LASTPIN (3700 800) $PN 2
J 0
(3710 780);
DISPLAY 0.617021 (3710 780);
PAINT ORANGE (3710 780);
FORCEPROP 1 LASTPIN (3700 1000) $PN 1
J 0
(3710 980);
DISPLAY 0.617021 (3710 980);
PAINT ORANGE (3710 980);
FORCEPROP 1 LAST VALUE 0.1UF
J 0
(3750 950);
DISPLAY 0.617021 (3750 950);
PAINT SKYBLUE (3750 950);
FORCEPROP 1 LAST VOLTAGE 16V
J 0
(3750 900);
DISPLAY 0.617021 (3750 900);
PAINT SKYBLUE (3750 900);
FORCEPROP 2 LAST BOM_COST SYS_CLOCK
J 0
(3750 1200);
DISPLAY 1.021277 (3750 1200);
PAINT ORANGE (3750 1200);
DISPLAY INVISIBLE (3750 1200);
FORCEPROP 2 LAST CDS_SEC 1
J 0
(3750 1050);
PAINT ORANGE (3750 1050);
DISPLAY INVISIBLE (3750 1050);
FORCEPROP 2 LAST SEC_TYPE 0402V
J 0
(3750 1100);
DISPLAY 1.021277 (3750 1100);
PAINT ORANGE (3750 1100);
DISPLAY INVISIBLE (3750 1100);
FORCEPROP 2 LAST SEC 1
J 0
(3750 1100);
DISPLAY 0.680851 (3750 1100);
PAINT MONO (3750 1100);
DISPLAY INVISIBLE (3750 1100);
FORCEPROP 2 LAST CDS_LOCATION C6P11
J 0
(3750 1000);
DISPLAY 0.617021 (3750 1000);
PAINT AQUA (3750 1000);
DISPLAY INVISIBLE (3750 1000);
FORCEPROP 2 LAST ROOM DB1200ZL
J 0
(3750 1100);
DISPLAY 1.021277 (3750 1100);
PAINT ORANGE (3750 1100);
DISPLAY INVISIBLE (3750 1100);
FORCEPROP 1 LAST PATH I16
J 0
(3750 1050);
DISPLAY 0.978723 (3750 1050);
PAINT WHITE (3750 1050);
DISPLAY INVISIBLE (3750 1050);
FORCEPROP 2 LAST CDS_LIB dev_discrete
J 0
(3700 900);
PAINT ORANGE (3700 900);
DISPLAY INVISIBLE (3700 900);
FORCEADD GND..1
(3700 550);
FORCEPROP 3 LASTPIN (3700 600) SIG_NAME GND\g
J 0
(3710 610);
DISPLAY 0.659574 (3710 610);
PAINT MONO (3710 610);
DISPLAY INVISIBLE (3710 610);
FORCEPROP 1 LAST PATH I17
J 0
(3775 550);
DISPLAY 0.872340 (3775 550);
PAINT AQUA (3775 550);
DISPLAY INVISIBLE (3775 550);
FORCEPROP 1 LAST SIZE 1B
J 0
(3775 500);
DISPLAY 1.127660 (3775 500);
PAINT ORANGE (3775 500);
DISPLAY INVISIBLE (3775 500);
FORCEPROP 1 LAST VOLTAGE 0.0V
J 0
(3655 507);
DISPLAY 0.340426 (3655 507);
PAINT SKYBLUE (3655 507);
DISPLAY INVISIBLE (3655 507);
FORCEPROP 2 LAST CDS_LIB mstr_symbols
J 0
(3700 550);
PAINT ORANGE (3700 550);
DISPLAY INVISIBLE (3700 550);
FORCEPROP 2 LAST ROOM DB1200ZL
J 0
(3375 625);
DISPLAY 1.127660 (3375 625);
PAINT WHITE (3375 625);
DISPLAY INVISIBLE (3375 625);
FORCEPROP 2 LAST BOM_COST SYS_CLOCK
J 0
(3250 625);
DISPLAY 1.617021 (3250 625);
PAINT WHITE (3250 625);
DISPLAY INVISIBLE (3250 625);
FORCEPROP 1 LAST BODY_TYPE PLUMBING
J 0
(3655 507);
DISPLAY 0.340426 (3655 507);
PAINT GREEN (3655 507);
DISPLAY INVISIBLE (3655 507);
FORCEPROP 1 LAST HDL_POWER GND
J 0
(3700 700);
PAINT GREEN (3700 700);
DISPLAY INVISIBLE (3700 700);
FORCEADD CAP_A..1
(-1550 3900);
FORCEPROP 1 LAST TOLERANCE 10%
J 0
(-1500 3850);
DISPLAY 0.617021 (-1500 3850);
PAINT SKYBLUE (-1500 3850);
FORCEPROP 1 LAST VALUE 0.1UF
J 0
(-1500 3950);
DISPLAY 0.617021 (-1500 3950);
PAINT SKYBLUE (-1500 3950);
FORCEPROP 1 LAST MATERIAL X7R
J 0
(-1500 3800);
DISPLAY 0.617021 (-1500 3800);
PAINT SKYBLUE (-1500 3800);
FORCEPROP 1 LASTPIN (-1550 3800) $PN 2
J 0
(-1540 3780);
DISPLAY 0.617021 (-1540 3780);
PAINT ORANGE (-1540 3780);
FORCEPROP 1 LASTPIN (-1550 4000) $PN 1
J 0
(-1540 3980);
DISPLAY 0.617021 (-1540 3980);
PAINT ORANGE (-1540 3980);
FORCEPROP 1 LAST LOCATION C4D24
J 0
(-1500 4000);
DISPLAY 0.617021 (-1500 4000);
PAINT AQUA (-1500 4000);
FORCEPROP 1 LAST PART_NUMBER A36096-030
J 0
(-1500 3750);
DISPLAY 0.617021 (-1500 3750);
PAINT BLUE (-1500 3750);
FORCEPROP 1 LAST VOLTAGE 16V
J 0
(-1500 3900);
DISPLAY 0.617021 (-1500 3900);
PAINT SKYBLUE (-1500 3900);
FORCEPROP 1 LAST PACK_TYPE 0402V
J 0
(-1500 3700);
DISPLAY 0.617021 (-1500 3700);
PAINT SKYBLUE (-1500 3700);
FORCEPROP 1 LAST PATH I18
J 0
(-1500 4050);
DISPLAY 0.978723 (-1500 4050);
PAINT WHITE (-1500 4050);
DISPLAY INVISIBLE (-1500 4050);
FORCEPROP 2 LAST ROOM DB1200ZL
J 0
(-1500 4100);
DISPLAY 1.021277 (-1500 4100);
PAINT ORANGE (-1500 4100);
DISPLAY INVISIBLE (-1500 4100);
FORCEPROP 2 LAST BOM_COST SYS_CLOCK
J 0
(-1500 4200);
DISPLAY 1.021277 (-1500 4200);
PAINT ORANGE (-1500 4200);
DISPLAY INVISIBLE (-1500 4200);
FORCEPROP 2 LAST CDS_SEC 1
J 0
(-1500 4050);
PAINT ORANGE (-1500 4050);
DISPLAY INVISIBLE (-1500 4050);
FORCEPROP 2 LAST SEC_TYPE 0402V
J 0
(-1500 4100);
DISPLAY 1.021277 (-1500 4100);
PAINT ORANGE (-1500 4100);
DISPLAY INVISIBLE (-1500 4100);
FORCEPROP 2 LAST SEC 1
J 0
(-1500 4100);
DISPLAY 0.680851 (-1500 4100);
PAINT MONO (-1500 4100);
DISPLAY INVISIBLE (-1500 4100);
FORCEPROP 2 LAST CDS_LOCATION C4D24
J 0
(-1500 4000);
DISPLAY 0.617021 (-1500 4000);
PAINT AQUA (-1500 4000);
DISPLAY INVISIBLE (-1500 4000);
FORCEPROP 2 LAST CDS_LIB dev_discrete
J 0
(-1550 3900);
PAINT ORANGE (-1550 3900);
DISPLAY INVISIBLE (-1550 3900);
FORCEADD CAP_A..1
(-1800 3900);
FORCEPROP 1 LASTPIN (-1800 3800) $PN 2
J 0
(-1790 3780);
DISPLAY 0.617021 (-1790 3780);
PAINT ORANGE (-1790 3780);
FORCEPROP 1 LASTPIN (-1800 4000) $PN 1
J 0
(-1790 3980);
DISPLAY 0.617021 (-1790 3980);
PAINT ORANGE (-1790 3980);
FORCEPROP 1 LAST TOLERANCE 10%
J 0
(-1750 3850);
DISPLAY 0.617021 (-1750 3850);
PAINT SKYBLUE (-1750 3850);
FORCEPROP 1 LAST MATERIAL X6S
J 0
(-1750 3800);
DISPLAY 0.617021 (-1750 3800);
PAINT SKYBLUE (-1750 3800);
FORCEPROP 1 LAST PART_NUMBER D97712-004
J 0
(-1750 3750);
DISPLAY 0.617021 (-1750 3750);
PAINT BLUE (-1750 3750);
FORCEPROP 1 LAST PACK_TYPE 0402V
J 0
(-1750 3700);
DISPLAY 0.617021 (-1750 3700);
PAINT SKYBLUE (-1750 3700);
FORCEPROP 1 LAST LOCATION C4D23
J 0
(-1750 4000);
DISPLAY 0.617021 (-1750 4000);
PAINT AQUA (-1750 4000);
FORCEPROP 1 LAST VALUE 1.0UF
J 0
(-1750 3950);
DISPLAY 0.617021 (-1750 3950);
PAINT SKYBLUE (-1750 3950);
FORCEPROP 1 LAST VOLTAGE 6.3V
J 0
(-1750 3900);
DISPLAY 0.617021 (-1750 3900);
PAINT SKYBLUE (-1750 3900);
FORCEPROP 2 LAST BOM_COST SYS_CLOCK
J 0
(-1750 4200);
DISPLAY 1.021277 (-1750 4200);
PAINT ORANGE (-1750 4200);
DISPLAY INVISIBLE (-1750 4200);
FORCEPROP 2 LAST CDS_SEC 1
J 0
(-1750 4050);
PAINT ORANGE (-1750 4050);
DISPLAY INVISIBLE (-1750 4050);
FORCEPROP 2 LAST SEC_TYPE 0402V
J 0
(-1750 4100);
DISPLAY 1.021277 (-1750 4100);
PAINT ORANGE (-1750 4100);
DISPLAY INVISIBLE (-1750 4100);
FORCEPROP 2 LAST SEC 1
J 0
(-1750 4100);
DISPLAY 0.680851 (-1750 4100);
PAINT MONO (-1750 4100);
DISPLAY INVISIBLE (-1750 4100);
FORCEPROP 1 LAST PATH I19
J 0
(-1750 4050);
DISPLAY 0.978723 (-1750 4050);
PAINT WHITE (-1750 4050);
DISPLAY INVISIBLE (-1750 4050);
FORCEPROP 2 LAST ROOM DB1200ZL
J 0
(-1750 4100);
DISPLAY 1.021277 (-1750 4100);
PAINT ORANGE (-1750 4100);
DISPLAY INVISIBLE (-1750 4100);
FORCEPROP 2 LAST CDS_LOCATION C4D23
J 0
(-1750 4000);
DISPLAY 0.617021 (-1750 4000);
PAINT AQUA (-1750 4000);
DISPLAY INVISIBLE (-1750 4000);
FORCEPROP 2 LAST CDS_LIB dev_discrete
J 0
(-1800 3900);
PAINT ORANGE (-1800 3900);
DISPLAY INVISIBLE (-1800 3900);
FORCEADD RES..1
(-2425 4125);
FORCEPROP 1 LAST VALUE 2.2
J 2
(-2450 4025);
DISPLAY 0.617021 (-2450 4025);
PAINT SKYBLUE (-2450 4025);
FORCEPROP 1 LAST TOLERANCE 1.0%
J 0
(-2425 4025);
DISPLAY 0.617021 (-2425 4025);
PAINT SKYBLUE (-2425 4025);
FORCEPROP 1 LAST PACK_TYPE 0603
J 0
(-2550 3925);
DISPLAY 0.617021 (-2550 3925);
PAINT SKYBLUE (-2550 3925);
FORCEPROP 1 LASTPIN (-2525 4125) $PN 1
J 0
(-2513 4137);
DISPLAY 0.617021 (-2513 4137);
PAINT ORANGE (-2513 4137);
FORCEPROP 1 LAST MATERIAL CHIP
J 0
(-2425 3975);
DISPLAY 0.617021 (-2425 3975);
PAINT SKYBLUE (-2425 3975);
FORCEPROP 1 LASTPIN (-2325 4125) $PN 2
J 0
(-2363 4137);
DISPLAY 0.617021 (-2363 4137);
PAINT ORANGE (-2363 4137);
FORCEPROP 1 LAST LOCATION R3D14
J 0
(-2475 4175);
DISPLAY 0.617021 (-2475 4175);
PAINT AQUA (-2475 4175);
FORCEPROP 1 LAST WATTAGE 1/10W
J 2
(-2450 3975);
DISPLAY 0.617021 (-2450 3975);
PAINT SKYBLUE (-2450 3975);
FORCEPROP 1 LAST PART_NUMBER G22026-127
J 0
(-2475 4225);
DISPLAY 0.617021 (-2475 4225);
PAINT BLUE (-2475 4225);
FORCEPROP 2 LAST BOM_COST SYS_CLOCK
J 0
(-2475 4425);
DISPLAY 1.021277 (-2475 4425);
PAINT ORANGE (-2475 4425);
DISPLAY INVISIBLE (-2475 4425);
FORCEPROP 2 LAST SEC_TYPE 0603
J 0
(-2475 4325);
DISPLAY 1.021277 (-2475 4325);
PAINT ORANGE (-2475 4325);
DISPLAY INVISIBLE (-2475 4325);
FORCEPROP 2 LAST SEC 1
J 0
(-2475 4325);
DISPLAY 0.680851 (-2475 4325);
PAINT MONO (-2475 4325);
DISPLAY INVISIBLE (-2475 4325);
FORCEPROP 2 LAST ROOM DB1200ZL
J 0
(-2475 4325);
DISPLAY 1.021277 (-2475 4325);
PAINT ORANGE (-2475 4325);
DISPLAY INVISIBLE (-2475 4325);
FORCEPROP 1 LAST PATH I21
J 0
(-2475 4275);
DISPLAY 0.978723 (-2475 4275);
PAINT WHITE (-2475 4275);
DISPLAY INVISIBLE (-2475 4275);
FORCEPROP 2 LAST CDS_LIB mstr_discrete
J 0
(-2425 4125);
PAINT ORANGE (-2425 4125);
DISPLAY INVISIBLE (-2425 4125);
FORCEPROP 2 LAST CDS_LOCATION R3D14
J 0
(-2475 4175);
DISPLAY 0.617021 (-2475 4175);
PAINT AQUA (-2475 4175);
DISPLAY INVISIBLE (-2475 4175);
FORCEADD GND..1
(-1550 3550);
FORCEPROP 3 LASTPIN (-1550 3600) SIG_NAME GND\g
J 0
(-1540 3610);
DISPLAY 0.659574 (-1540 3610);
PAINT MONO (-1540 3610);
DISPLAY INVISIBLE (-1540 3610);
FORCEPROP 1 LAST PATH I22
J 0
(-1475 3550);
DISPLAY 0.872340 (-1475 3550);
PAINT AQUA (-1475 3550);
DISPLAY INVISIBLE (-1475 3550);
FORCEPROP 1 LAST SIZE 1B
J 0
(-1475 3500);
DISPLAY 1.127660 (-1475 3500);
PAINT ORANGE (-1475 3500);
DISPLAY INVISIBLE (-1475 3500);
FORCEPROP 2 LAST CDS_LIB mstr_symbols
J 0
(-1550 3550);
PAINT ORANGE (-1550 3550);
DISPLAY INVISIBLE (-1550 3550);
FORCEPROP 2 LAST BOM_COST SYS_CLOCK
J 0
(-2000 3625);
DISPLAY 1.617021 (-2000 3625);
PAINT WHITE (-2000 3625);
DISPLAY INVISIBLE (-2000 3625);
FORCEPROP 2 LAST ROOM DB1200ZL
J 0
(-1875 3625);
DISPLAY 1.127660 (-1875 3625);
PAINT WHITE (-1875 3625);
DISPLAY INVISIBLE (-1875 3625);
FORCEPROP 1 LAST VOLTAGE 0.0V
J 0
(-1595 3507);
DISPLAY 0.340426 (-1595 3507);
PAINT SKYBLUE (-1595 3507);
DISPLAY INVISIBLE (-1595 3507);
FORCEPROP 1 LAST BODY_TYPE PLUMBING
J 0
(-1595 3507);
DISPLAY 0.340426 (-1595 3507);
PAINT GREEN (-1595 3507);
DISPLAY INVISIBLE (-1595 3507);
FORCEPROP 1 LAST HDL_POWER GND
J 0
(-1550 3700);
PAINT GREEN (-1550 3700);
DISPLAY INVISIBLE (-1550 3700);
FORCEADD VCC_CORE..1
(3700 1300);
FORCEPROP 3 LASTPIN (3700 1250) SIG_NAME P3V3_DB1200\g
J 0
(3710 1260);
DISPLAY 0.659574 (3710 1260);
PAINT MONO (3710 1260);
DISPLAY INVISIBLE (3710 1260);
FORCEPROP 1 LAST HDL_POWER P3V3_DB1200
J 1
(3750 1350);
DISPLAY 0.617021 (3750 1350);
PAINT GREEN (3750 1350);
FORCEPROP 1 LAST PATH I23
J 0
(3750 1325);
DISPLAY 0.872340 (3750 1325);
PAINT AQUA (3750 1325);
DISPLAY INVISIBLE (3750 1325);
FORCEPROP 2 LAST CDS_LIB mstr_symbols
J 0
(3700 1300);
PAINT ORANGE (3700 1300);
DISPLAY INVISIBLE (3700 1300);
FORCEPROP 0 LAST VOLTAGE 5
J 0
(3700 1300);
PAINT SKYBLUE (3700 1300);
DISPLAY INVISIBLE (3700 1300);
FORCEADD VCC_CORE..1
(-2800 4250);
FORCEPROP 3 LASTPIN (-2800 4200) SIG_NAME P3V3_DB1200\g
J 0
(-2790 4210);
DISPLAY 0.659574 (-2790 4210);
PAINT MONO (-2790 4210);
DISPLAY INVISIBLE (-2790 4210);
FORCEPROP 1 LAST HDL_POWER P3V3_DB1200
J 1
(-2750 4300);
DISPLAY 0.617021 (-2750 4300);
PAINT GREEN (-2750 4300);
FORCEPROP 1 LAST PATH I24
J 0
(-2750 4275);
DISPLAY 0.872340 (-2750 4275);
PAINT AQUA (-2750 4275);
DISPLAY INVISIBLE (-2750 4275);
FORCEPROP 2 LAST CDS_LIB mstr_symbols
J 0
(-2800 4250);
PAINT ORANGE (-2800 4250);
DISPLAY INVISIBLE (-2800 4250);
FORCEPROP 0 LAST VOLTAGE 5
J 0
(-2800 4250);
PAINT SKYBLUE (-2800 4250);
DISPLAY INVISIBLE (-2800 4250);
FORCEADD VCC_CORE..1
(-825 3925);
FORCEPROP 3 LASTPIN (-825 3875) SIG_NAME P3V3_DB1200\g
J 0
(-815 3885);
DISPLAY 0.659574 (-815 3885);
PAINT MONO (-815 3885);
DISPLAY INVISIBLE (-815 3885);
FORCEPROP 1 LAST HDL_POWER P3V3_DB1200
J 1
(-775 3975);
DISPLAY 0.617021 (-775 3975);
PAINT GREEN (-775 3975);
FORCEPROP 0 LAST VOLTAGE 5
J 0
(-825 3925);
PAINT SKYBLUE (-825 3925);
DISPLAY INVISIBLE (-825 3925);
FORCEPROP 2 LAST CDS_LIB mstr_symbols
J 0
(-825 3925);
PAINT ORANGE (-825 3925);
DISPLAY INVISIBLE (-825 3925);
FORCEPROP 1 LAST PATH I25
J 0
(-775 3950);
DISPLAY 0.872340 (-775 3950);
PAINT AQUA (-775 3950);
DISPLAY INVISIBLE (-775 3950);
FORCEADD RES..1
(-2825 3400);
FORCEPROP 1 LAST PART_NUMBER G22026-127
J 0
(-2875 3500);
DISPLAY 0.617021 (-2875 3500);
PAINT BLUE (-2875 3500);
FORCEPROP 1 LAST LOCATION R6P25
J 0
(-2875 3450);
DISPLAY 0.617021 (-2875 3450);
PAINT AQUA (-2875 3450);
FORCEPROP 1 LASTPIN (-2925 3400) $PN 1
J 0
(-2913 3412);
DISPLAY 0.617021 (-2913 3412);
PAINT ORANGE (-2913 3412);
FORCEPROP 1 LASTPIN (-2725 3400) $PN 2
J 0
(-2763 3412);
DISPLAY 0.617021 (-2763 3412);
PAINT ORANGE (-2763 3412);
FORCEPROP 1 LAST VALUE 2.2
J 2
(-2850 3300);
DISPLAY 0.617021 (-2850 3300);
PAINT SKYBLUE (-2850 3300);
FORCEPROP 1 LAST PACK_TYPE 0603
J 0
(-2950 3200);
DISPLAY 0.617021 (-2950 3200);
PAINT SKYBLUE (-2950 3200);
FORCEPROP 1 LAST WATTAGE 1/10W
J 2
(-2850 3250);
DISPLAY 0.617021 (-2850 3250);
PAINT SKYBLUE (-2850 3250);
FORCEPROP 1 LAST TOLERANCE 1.0%
J 0
(-2825 3300);
DISPLAY 0.617021 (-2825 3300);
PAINT SKYBLUE (-2825 3300);
FORCEPROP 1 LAST MATERIAL CHIP
J 0
(-2825 3250);
DISPLAY 0.617021 (-2825 3250);
PAINT SKYBLUE (-2825 3250);
FORCEPROP 2 LAST BOM_COST SYS_CLOCK
J 0
(-2875 3700);
DISPLAY 1.021277 (-2875 3700);
PAINT ORANGE (-2875 3700);
DISPLAY INVISIBLE (-2875 3700);
FORCEPROP 2 LAST SEC_TYPE 0603
J 0
(-2875 3600);
DISPLAY 1.021277 (-2875 3600);
PAINT ORANGE (-2875 3600);
DISPLAY INVISIBLE (-2875 3600);
FORCEPROP 2 LAST SEC 1
J 0
(-2875 3600);
DISPLAY 0.680851 (-2875 3600);
PAINT MONO (-2875 3600);
DISPLAY INVISIBLE (-2875 3600);
FORCEPROP 1 LAST PATH I26
J 0
(-2875 3550);
DISPLAY 0.978723 (-2875 3550);
PAINT WHITE (-2875 3550);
DISPLAY INVISIBLE (-2875 3550);
FORCEPROP 2 LAST ROOM DB1200ZL
J 0
(-2875 3600);
DISPLAY 1.021277 (-2875 3600);
PAINT ORANGE (-2875 3600);
DISPLAY INVISIBLE (-2875 3600);
FORCEPROP 2 LAST CDS_LIB mstr_discrete
J 0
(-2825 3400);
PAINT ORANGE (-2825 3400);
DISPLAY INVISIBLE (-2825 3400);
FORCEPROP 2 LAST CDS_LOCATION R6P25
J 0
(-2875 3450);
DISPLAY 0.617021 (-2875 3450);
PAINT AQUA (-2875 3450);
DISPLAY INVISIBLE (-2875 3450);
FORCEADD VCC_CORE..1
(-3125 3550);
FORCEPROP 3 LASTPIN (-3125 3500) SIG_NAME P3V3_DB1200\g
J 0
(-3115 3510);
DISPLAY 0.659574 (-3115 3510);
PAINT MONO (-3115 3510);
DISPLAY INVISIBLE (-3115 3510);
FORCEPROP 1 LAST HDL_POWER P3V3_DB1200
J 1
(-3075 3600);
DISPLAY 0.617021 (-3075 3600);
PAINT GREEN (-3075 3600);
FORCEPROP 2 LAST CDS_LIB mstr_symbols
J 0
(-3125 3550);
PAINT ORANGE (-3125 3550);
DISPLAY INVISIBLE (-3125 3550);
FORCEPROP 0 LAST VOLTAGE 5
J 0
(-3125 3550);
PAINT SKYBLUE (-3125 3550);
DISPLAY INVISIBLE (-3125 3550);
FORCEPROP 1 LAST PATH I27
J 0
(-3075 3575);
DISPLAY 0.872340 (-3075 3575);
PAINT AQUA (-3075 3575);
DISPLAY INVISIBLE (-3075 3575);
FORCEADD CAP_A..1
(-2325 3225);
FORCEPROP 1 LAST VALUE 0.1UF
J 0
(-2275 3275);
DISPLAY 0.617021 (-2275 3275);
PAINT SKYBLUE (-2275 3275);
FORCEPROP 1 LAST VOLTAGE 16V
J 0
(-2275 3225);
DISPLAY 0.617021 (-2275 3225);
PAINT SKYBLUE (-2275 3225);
FORCEPROP 1 LAST TOLERANCE 10%
J 0
(-2275 3175);
DISPLAY 0.617021 (-2275 3175);
PAINT SKYBLUE (-2275 3175);
FORCEPROP 1 LAST MATERIAL X7R
J 0
(-2275 3125);
DISPLAY 0.617021 (-2275 3125);
PAINT SKYBLUE (-2275 3125);
FORCEPROP 1 LAST PART_NUMBER A36096-030
J 0
(-2275 3075);
DISPLAY 0.617021 (-2275 3075);
PAINT BLUE (-2275 3075);
FORCEPROP 1 LASTPIN (-2325 3125) $PN 2
J 0
(-2315 3105);
DISPLAY 0.617021 (-2315 3105);
PAINT ORANGE (-2315 3105);
FORCEPROP 1 LASTPIN (-2325 3325) $PN 1
J 0
(-2315 3305);
DISPLAY 0.617021 (-2315 3305);
PAINT ORANGE (-2315 3305);
FORCEPROP 1 LAST LOCATION C4D22
J 0
(-2275 3325);
DISPLAY 0.617021 (-2275 3325);
PAINT AQUA (-2275 3325);
FORCEPROP 1 LAST PACK_TYPE 0402V
J 0
(-2275 3025);
DISPLAY 0.617021 (-2275 3025);
PAINT SKYBLUE (-2275 3025);
FORCEPROP 2 LAST BOM_COST SYS_CLOCK
J 0
(-2275 3525);
DISPLAY 1.021277 (-2275 3525);
PAINT ORANGE (-2275 3525);
DISPLAY INVISIBLE (-2275 3525);
FORCEPROP 1 LAST PATH I28
J 0
(-2275 3375);
DISPLAY 0.978723 (-2275 3375);
PAINT WHITE (-2275 3375);
DISPLAY INVISIBLE (-2275 3375);
FORCEPROP 2 LAST ROOM DB1200ZL
J 0
(-2275 3425);
DISPLAY 1.021277 (-2275 3425);
PAINT ORANGE (-2275 3425);
DISPLAY INVISIBLE (-2275 3425);
FORCEPROP 2 LAST CDS_LOCATION C4D22
J 0
(-2275 3325);
DISPLAY 0.617021 (-2275 3325);
PAINT AQUA (-2275 3325);
DISPLAY INVISIBLE (-2275 3325);
FORCEPROP 2 LAST CDS_SEC 1
J 0
(-2275 3375);
PAINT ORANGE (-2275 3375);
DISPLAY INVISIBLE (-2275 3375);
FORCEPROP 2 LAST SEC_TYPE 0402V
J 0
(-2275 3425);
DISPLAY 1.021277 (-2275 3425);
PAINT ORANGE (-2275 3425);
DISPLAY INVISIBLE (-2275 3425);
FORCEPROP 2 LAST SEC 1
J 0
(-2275 3425);
DISPLAY 0.680851 (-2275 3425);
PAINT MONO (-2275 3425);
DISPLAY INVISIBLE (-2275 3425);
FORCEPROP 2 LAST CDS_LIB dev_discrete
J 0
(-2325 3225);
PAINT ORANGE (-2325 3225);
DISPLAY INVISIBLE (-2325 3225);
FORCEADD GND..1
(-2325 2900);
FORCEPROP 3 LASTPIN (-2325 2950) SIG_NAME GND\g
J 0
(-2315 2960);
DISPLAY 0.659574 (-2315 2960);
PAINT MONO (-2315 2960);
DISPLAY INVISIBLE (-2315 2960);
FORCEPROP 2 LAST BOM_COST SYS_CLOCK
J 0
(-2775 2975);
DISPLAY 1.617021 (-2775 2975);
PAINT WHITE (-2775 2975);
DISPLAY INVISIBLE (-2775 2975);
FORCEPROP 2 LAST ROOM DB1200ZL
J 0
(-2650 2975);
DISPLAY 1.127660 (-2650 2975);
PAINT WHITE (-2650 2975);
DISPLAY INVISIBLE (-2650 2975);
FORCEPROP 1 LAST VOLTAGE 0.0V
J 0
(-2370 2857);
DISPLAY 0.340426 (-2370 2857);
PAINT SKYBLUE (-2370 2857);
DISPLAY INVISIBLE (-2370 2857);
FORCEPROP 2 LAST CDS_LIB mstr_symbols
J 0
(-2325 2900);
PAINT ORANGE (-2325 2900);
DISPLAY INVISIBLE (-2325 2900);
FORCEPROP 1 LAST SIZE 1B
J 0
(-2250 2850);
DISPLAY 1.127660 (-2250 2850);
PAINT ORANGE (-2250 2850);
DISPLAY INVISIBLE (-2250 2850);
FORCEPROP 1 LAST PATH I29
J 0
(-2250 2900);
DISPLAY 0.872340 (-2250 2900);
PAINT AQUA (-2250 2900);
DISPLAY INVISIBLE (-2250 2900);
FORCEPROP 1 LAST BODY_TYPE PLUMBING
J 0
(-2370 2857);
DISPLAY 0.340426 (-2370 2857);
PAINT GREEN (-2370 2857);
DISPLAY INVISIBLE (-2370 2857);
FORCEPROP 1 LAST HDL_POWER GND
J 0
(-2325 3050);
PAINT GREEN (-2325 3050);
DISPLAY INVISIBLE (-2325 3050);
FORCEADD CAP_A..1
(-2575 3225);
FORCEPROP 1 LASTPIN (-2575 3325) $PN 1
J 0
(-2565 3305);
DISPLAY 0.617021 (-2565 3305);
PAINT ORANGE (-2565 3305);
FORCEPROP 1 LASTPIN (-2575 3125) $PN 2
J 0
(-2565 3105);
DISPLAY 0.617021 (-2565 3105);
PAINT ORANGE (-2565 3105);
FORCEPROP 1 LAST LOCATION C4D27
J 0
(-2525 3325);
DISPLAY 0.617021 (-2525 3325);
PAINT AQUA (-2525 3325);
FORCEPROP 1 LAST VALUE 1.0UF
J 0
(-2525 3275);
DISPLAY 0.617021 (-2525 3275);
PAINT SKYBLUE (-2525 3275);
FORCEPROP 1 LAST TOLERANCE 10%
J 0
(-2525 3175);
DISPLAY 0.617021 (-2525 3175);
PAINT SKYBLUE (-2525 3175);
FORCEPROP 1 LAST MATERIAL X6S
J 0
(-2525 3125);
DISPLAY 0.617021 (-2525 3125);
PAINT SKYBLUE (-2525 3125);
FORCEPROP 1 LAST VOLTAGE 6.3V
J 0
(-2525 3225);
DISPLAY 0.617021 (-2525 3225);
PAINT SKYBLUE (-2525 3225);
FORCEPROP 1 LAST PART_NUMBER D97712-004
J 0
(-2525 3075);
DISPLAY 0.617021 (-2525 3075);
PAINT BLUE (-2525 3075);
FORCEPROP 1 LAST PACK_TYPE 0402V
J 0
(-2525 3025);
DISPLAY 0.617021 (-2525 3025);
PAINT SKYBLUE (-2525 3025);
FORCEPROP 2 LAST BOM_COST SYS_CLOCK
J 0
(-2525 3525);
DISPLAY 1.021277 (-2525 3525);
PAINT ORANGE (-2525 3525);
DISPLAY INVISIBLE (-2525 3525);
FORCEPROP 2 LAST CDS_LOCATION C4D27
J 0
(-2525 3325);
DISPLAY 0.617021 (-2525 3325);
PAINT AQUA (-2525 3325);
DISPLAY INVISIBLE (-2525 3325);
FORCEPROP 2 LAST CDS_SEC 1
J 0
(-2525 3375);
PAINT ORANGE (-2525 3375);
DISPLAY INVISIBLE (-2525 3375);
FORCEPROP 2 LAST SEC_TYPE 0402V
J 0
(-2525 3425);
DISPLAY 1.021277 (-2525 3425);
PAINT ORANGE (-2525 3425);
DISPLAY INVISIBLE (-2525 3425);
FORCEPROP 2 LAST SEC 1
J 0
(-2525 3425);
DISPLAY 0.680851 (-2525 3425);
PAINT MONO (-2525 3425);
DISPLAY INVISIBLE (-2525 3425);
FORCEPROP 1 LAST PATH I30
J 0
(-2525 3375);
DISPLAY 0.978723 (-2525 3375);
PAINT WHITE (-2525 3375);
DISPLAY INVISIBLE (-2525 3375);
FORCEPROP 2 LAST ROOM DB1200ZL
J 0
(-2525 3425);
DISPLAY 1.021277 (-2525 3425);
PAINT ORANGE (-2525 3425);
DISPLAY INVISIBLE (-2525 3425);
FORCEPROP 2 LAST CDS_LIB dev_discrete
J 0
(-2575 3225);
PAINT ORANGE (-2575 3225);
DISPLAY INVISIBLE (-2575 3225);
FORCEADD OFFPAGE..1
(-1175 3300);
FORCEPROP 2 LAST $XR0 102 
J 0
(-1427 3300);
DISPLAY 0.638298 (-1427 3300);
PAINT MONO (-1427 3300);
FORCEPROP 2 LAST CDS_LIB mstr_standard
J 0
(-1175 3300);
PAINT ORANGE (-1175 3300);
DISPLAY INVISIBLE (-1175 3300);
FORCEPROP 2 LAST PATH I31
J 0
(-1125 3375);
DISPLAY 1.021277 (-1125 3375);
PAINT ORANGE (-1125 3375);
DISPLAY INVISIBLE (-1125 3375);
FORCEPROP 1 LAST OFFPAGE TRUE
J 0
(-850 3175);
PAINT GREEN (-850 3175);
DISPLAY INVISIBLE (-850 3175);
FORCEPROP 1 LAST COMMENT_BODY TRUE
J 0
(-1050 3200);
DISPLAY 1.404255 (-1050 3200);
PAINT PEACH (-1050 3200);
DISPLAY INVISIBLE (-1050 3200);
FORCEADD OFFPAGE..1
(-1175 3250);
FORCEPROP 2 LAST $XR0 102 
J 0
(-1427 3250);
DISPLAY 0.638298 (-1427 3250);
PAINT MONO (-1427 3250);
FORCEPROP 2 LAST PATH I32
J 0
(-1125 3325);
DISPLAY 1.021277 (-1125 3325);
PAINT ORANGE (-1125 3325);
DISPLAY INVISIBLE (-1125 3325);
FORCEPROP 2 LAST CDS_LIB mstr_standard
J 0
(-1175 3250);
PAINT ORANGE (-1175 3250);
DISPLAY INVISIBLE (-1175 3250);
FORCEPROP 1 LAST OFFPAGE TRUE
J 0
(-850 3125);
PAINT GREEN (-850 3125);
DISPLAY INVISIBLE (-850 3125);
FORCEPROP 1 LAST COMMENT_BODY TRUE
J 0
(-1050 3150);
DISPLAY 1.404255 (-1050 3150);
PAINT PEACH (-1050 3150);
DISPLAY INVISIBLE (-1050 3150);
FORCEADD OFFPAGE..1
(-1175 3100);
FORCEPROP 2 LAST $XR0 102 
J 0
(-1457 3100);
DISPLAY 0.638298 (-1457 3100);
PAINT MONO (-1457 3100);
FORCEPROP 2 LAST CDS_LIB mstr_standard
J 0
(-1175 3100);
DISPLAY 1.617021 (-1175 3100);
PAINT MONO (-1175 3100);
DISPLAY INVISIBLE (-1175 3100);
FORCEPROP 2 LAST PATH I33
J 0
(-1425 3150);
DISPLAY 1.021277 (-1425 3150);
PAINT ORANGE (-1425 3150);
DISPLAY INVISIBLE (-1425 3150);
FORCEPROP 1 LAST OFFPAGE TRUE
J 0
(-850 2975);
PAINT GREEN (-850 2975);
DISPLAY INVISIBLE (-850 2975);
FORCEPROP 1 LAST COMMENT_BODY TRUE
J 0
(-1050 3000);
DISPLAY 1.404255 (-1050 3000);
PAINT PEACH (-1050 3000);
DISPLAY INVISIBLE (-1050 3000);
FORCEADD OFFPAGE..3
R 2
(-1175 3150);
FORCEPROP 2 LAST $XR0 102 
J 0
(-1455 3150);
DISPLAY 0.638298 (-1455 3150);
PAINT MONO (-1455 3150);
FORCEPROP 2 LAST PATH I34
J 2
(-925 3200);
DISPLAY 1.021277 (-925 3200);
PAINT ORANGE (-925 3200);
DISPLAY INVISIBLE (-925 3200);
FORCEPROP 2 LAST CDS_LIB mstr_standard
J 2
(-1175 3150);
DISPLAY 1.617021 (-1175 3150);
PAINT MONO (-1175 3150);
DISPLAY INVISIBLE (-1175 3150);
FORCEPROP 1 LAST OFFPAGE TRUE
J 2
(-1500 3025);
DISPLAY 0.872340 (-1500 3025);
PAINT GREEN (-1500 3025);
DISPLAY INVISIBLE (-1500 3025);
FORCEPROP 1 LAST COMMENT_BODY TRUE
J 2
(-1125 3050);
DISPLAY 0.872340 (-1125 3050);
PAINT GREEN (-1125 3050);
DISPLAY INVISIBLE (-1125 3050);
FORCEADD OFFPAGE..1
(-1200 1550);
FORCEPROP 2 LAST $XR0 102 
J 0
(-1482 1550);
DISPLAY 0.638298 (-1482 1550);
PAINT MONO (-1482 1550);
FORCEPROP 2 LAST CDS_LIB mstr_standard
J 0
(-1200 1550);
PAINT ORANGE (-1200 1550);
DISPLAY INVISIBLE (-1200 1550);
FORCEPROP 2 LAST PATH I35
J 0
(-1150 1625);
DISPLAY 1.021277 (-1150 1625);
PAINT ORANGE (-1150 1625);
DISPLAY INVISIBLE (-1150 1625);
FORCEPROP 1 LAST OFFPAGE TRUE
J 0
(-875 1425);
PAINT GREEN (-875 1425);
DISPLAY INVISIBLE (-875 1425);
FORCEPROP 1 LAST COMMENT_BODY TRUE
J 0
(-1075 1450);
DISPLAY 1.404255 (-1075 1450);
PAINT PEACH (-1075 1450);
DISPLAY INVISIBLE (-1075 1450);
FORCEADD OFFPAGE..1
(-1200 1500);
FORCEPROP 2 LAST $XR0 102 
J 0
(-1482 1500);
DISPLAY 0.638298 (-1482 1500);
PAINT MONO (-1482 1500);
FORCEPROP 2 LAST CDS_LIB mstr_standard
J 0
(-1200 1500);
PAINT ORANGE (-1200 1500);
DISPLAY INVISIBLE (-1200 1500);
FORCEPROP 2 LAST PATH I36
J 0
(-1150 1575);
DISPLAY 1.021277 (-1150 1575);
PAINT ORANGE (-1150 1575);
DISPLAY INVISIBLE (-1150 1575);
FORCEPROP 1 LAST OFFPAGE TRUE
J 0
(-875 1375);
PAINT GREEN (-875 1375);
DISPLAY INVISIBLE (-875 1375);
FORCEPROP 1 LAST COMMENT_BODY TRUE
J 0
(-1075 1400);
DISPLAY 1.404255 (-1075 1400);
PAINT PEACH (-1075 1400);
DISPLAY INVISIBLE (-1075 1400);
FORCEADD RES..2
(-2850 2850);
FORCEPROP 1 LAST PART_NUMBER G21796-016
J 0
(-2810 2725);
DISPLAY 0.617021 (-2810 2725);
PAINT BLUE (-2810 2725);
FORCEPROP 1 LASTPIN (-2850 2750) $PN 2
J 0
(-2845 2760);
DISPLAY 0.617021 (-2845 2760);
PAINT ORANGE (-2845 2760);
FORCEPROP 1 LASTPIN (-2850 2950) $PN 1
J 0
(-2845 2912);
DISPLAY 0.617021 (-2845 2912);
PAINT ORANGE (-2845 2912);
FORCEPROP 1 LAST LOCATION R4D38
J 0
(-2805 2975);
DISPLAY 0.617021 (-2805 2975);
PAINT AQUA (-2805 2975);
FORCEPROP 1 LAST VALUE 10.0K
J 0
(-2805 2925);
DISPLAY 0.617021 (-2805 2925);
PAINT SKYBLUE (-2805 2925);
FORCEPROP 1 LAST TOLERANCE 1%
J 0
(-2805 2875);
DISPLAY 0.617021 (-2805 2875);
PAINT SKYBLUE (-2805 2875);
FORCEPROP 1 LAST PACK_TYPE 0402
J 0
(-2810 2675);
DISPLAY 0.617021 (-2810 2675);
PAINT SKYBLUE (-2810 2675);
FORCEPROP 1 LAST MATERIAL EMPTY
J 0
(-2810 2775);
DISPLAY 0.617021 (-2810 2775);
PAINT RED (-2810 2775);
FORCEPROP 1 LAST WATTAGE 1/16W
J 0
(-2810 2825);
DISPLAY 0.617021 (-2810 2825);
PAINT SKYBLUE (-2810 2825);
FORCEPROP 2 LAST ROOM DB1200ZL
J 0
(-2800 3075);
DISPLAY 1.021277 (-2800 3075);
PAINT ORANGE (-2800 3075);
DISPLAY INVISIBLE (-2800 3075);
FORCEPROP 1 LAST PATH I37
J 0
(-2800 3025);
DISPLAY 0.978723 (-2800 3025);
PAINT WHITE (-2800 3025);
DISPLAY INVISIBLE (-2800 3025);
FORCEPROP 2 LAST SEC 1
J 0
(-2800 3075);
DISPLAY 0.680851 (-2800 3075);
PAINT MONO (-2800 3075);
DISPLAY INVISIBLE (-2800 3075);
FORCEPROP 2 LAST SEC_TYPE 0402
J 0
(-2800 3075);
DISPLAY 1.021277 (-2800 3075);
PAINT ORANGE (-2800 3075);
DISPLAY INVISIBLE (-2800 3075);
FORCEPROP 2 LAST BOM_COST SYS_CLOCK
J 0
(-2800 3175);
DISPLAY 1.021277 (-2800 3175);
PAINT ORANGE (-2800 3175);
DISPLAY INVISIBLE (-2800 3175);
FORCEPROP 2 LAST CDS_LOCATION R4D38
J 0
(-2805 2975);
DISPLAY 0.617021 (-2805 2975);
PAINT AQUA (-2805 2975);
DISPLAY INVISIBLE (-2805 2975);
FORCEPROP 2 LAST CDS_LIB mstr_discrete
J 0
(-2850 2850);
PAINT ORANGE (-2850 2850);
DISPLAY INVISIBLE (-2850 2850);
FORCEADD RES..2
(-3225 2850);
FORCEPROP 1 LASTPIN (-3225 2950) $PN 1
J 0
(-3220 2912);
DISPLAY 0.617021 (-3220 2912);
PAINT ORANGE (-3220 2912);
FORCEPROP 1 LASTPIN (-3225 2750) $PN 2
J 0
(-3220 2760);
DISPLAY 0.617021 (-3220 2760);
PAINT ORANGE (-3220 2760);
FORCEPROP 1 LAST LOCATION R4D35
J 0
(-3180 2975);
DISPLAY 0.617021 (-3180 2975);
PAINT AQUA (-3180 2975);
FORCEPROP 1 LAST VALUE 10.0K
J 0
(-3180 2925);
DISPLAY 0.617021 (-3180 2925);
PAINT SKYBLUE (-3180 2925);
FORCEPROP 1 LAST TOLERANCE 1%
J 0
(-3180 2875);
DISPLAY 0.617021 (-3180 2875);
PAINT SKYBLUE (-3180 2875);
FORCEPROP 1 LAST WATTAGE 1/16W
J 0
(-3185 2825);
DISPLAY 0.617021 (-3185 2825);
PAINT SKYBLUE (-3185 2825);
FORCEPROP 1 LAST MATERIAL EMPTY
J 0
(-3185 2775);
DISPLAY 0.617021 (-3185 2775);
PAINT RED (-3185 2775);
FORCEPROP 1 LAST PACK_TYPE 0402
J 0
(-3185 2675);
DISPLAY 0.617021 (-3185 2675);
PAINT SKYBLUE (-3185 2675);
FORCEPROP 1 LAST PART_NUMBER G21796-016
J 0
(-3185 2725);
DISPLAY 0.617021 (-3185 2725);
PAINT BLUE (-3185 2725);
FORCEPROP 2 LAST CDS_LIB mstr_discrete
J 0
(-3225 2850);
PAINT ORANGE (-3225 2850);
DISPLAY INVISIBLE (-3225 2850);
FORCEPROP 2 LAST CDS_LOCATION R4D35
J 0
(-3180 2975);
DISPLAY 0.617021 (-3180 2975);
PAINT AQUA (-3180 2975);
DISPLAY INVISIBLE (-3180 2975);
FORCEPROP 2 LAST BOM_COST SYS_CLOCK
J 0
(-3175 3175);
DISPLAY 1.021277 (-3175 3175);
PAINT ORANGE (-3175 3175);
DISPLAY INVISIBLE (-3175 3175);
FORCEPROP 2 LAST SEC_TYPE 0402
J 0
(-3175 3075);
DISPLAY 1.021277 (-3175 3075);
PAINT ORANGE (-3175 3075);
DISPLAY INVISIBLE (-3175 3075);
FORCEPROP 2 LAST SEC 1
J 0
(-3175 3075);
DISPLAY 0.680851 (-3175 3075);
PAINT MONO (-3175 3075);
DISPLAY INVISIBLE (-3175 3075);
FORCEPROP 1 LAST PATH I38
J 0
(-3175 3025);
DISPLAY 0.978723 (-3175 3025);
PAINT WHITE (-3175 3025);
DISPLAY INVISIBLE (-3175 3025);
FORCEPROP 2 LAST ROOM DB1200ZL
J 0
(-3175 3075);
DISPLAY 1.021277 (-3175 3075);
PAINT ORANGE (-3175 3075);
DISPLAY INVISIBLE (-3175 3075);
FORCEADD OFFPAGE..1
(-1725 2350);
FORCEPROP 2 LAST $XR0 114 
J 0
(-1977 2350);
DISPLAY 0.638298 (-1977 2350);
PAINT MONO (-1977 2350);
FORCEPROP 2 LAST CDS_LIB mstr_standard
J 0
(-1725 2350);
PAINT ORANGE (-1725 2350);
DISPLAY INVISIBLE (-1725 2350);
FORCEPROP 2 LAST PATH I4
J 0
(-1675 2425);
DISPLAY 1.021277 (-1675 2425);
PAINT ORANGE (-1675 2425);
DISPLAY INVISIBLE (-1675 2425);
FORCEPROP 1 LAST OFFPAGE TRUE
J 0
(-1400 2225);
PAINT GREEN (-1400 2225);
DISPLAY INVISIBLE (-1400 2225);
FORCEPROP 1 LAST COMMENT_BODY TRUE
J 0
(-1600 2250);
DISPLAY 1.404255 (-1600 2250);
PAINT PEACH (-1600 2250);
DISPLAY INVISIBLE (-1600 2250);
FORCEADD OFFPAGE..2
(-1950 2700);
FORCEPROP 2 LAST $XR0 102 
J 0
(-1761 2700);
DISPLAY 0.638298 (-1761 2700);
PAINT MONO (-1761 2700);
FORCEPROP 2 LAST PATH I41
J 0
(-1900 2775);
DISPLAY 1.021277 (-1900 2775);
PAINT ORANGE (-1900 2775);
DISPLAY INVISIBLE (-1900 2775);
FORCEPROP 2 LAST CDS_LIB mstr_standard
J 0
(-1950 2700);
PAINT ORANGE (-1950 2700);
DISPLAY INVISIBLE (-1950 2700);
FORCEPROP 1 LAST OFFPAGE TRUE
J 0
(-1625 2575);
DISPLAY 0.872340 (-1625 2575);
PAINT GREEN (-1625 2575);
DISPLAY INVISIBLE (-1625 2575);
FORCEPROP 1 LAST COMMENT_BODY TRUE
J 0
(-1995 2605);
DISPLAY 0.872340 (-1995 2605);
PAINT GREEN (-1995 2605);
DISPLAY INVISIBLE (-1995 2605);
FORCEADD OFFPAGE..2
(-1950 2650);
FORCEPROP 2 LAST $XR0 102 
J 0
(-1761 2650);
DISPLAY 0.638298 (-1761 2650);
PAINT MONO (-1761 2650);
FORCEPROP 2 LAST PATH I42
J 0
(-1775 2725);
DISPLAY 1.021277 (-1775 2725);
PAINT ORANGE (-1775 2725);
DISPLAY INVISIBLE (-1775 2725);
FORCEPROP 2 LAST CDS_LIB mstr_standard
J 0
(-1950 2650);
PAINT ORANGE (-1950 2650);
DISPLAY INVISIBLE (-1950 2650);
FORCEPROP 1 LAST OFFPAGE TRUE
J 0
(-1625 2525);
DISPLAY 0.872340 (-1625 2525);
PAINT GREEN (-1625 2525);
DISPLAY INVISIBLE (-1625 2525);
FORCEPROP 1 LAST COMMENT_BODY TRUE
J 0
(-1995 2555);
DISPLAY 0.872340 (-1995 2555);
PAINT GREEN (-1995 2555);
DISPLAY INVISIBLE (-1995 2555);
FORCEADD VCC_CORE..1
(-3225 3150);
FORCEPROP 3 LASTPIN (-3225 3100) SIG_NAME P3V3_DB1200\g
J 0
(-3215 3110);
DISPLAY 0.659574 (-3215 3110);
PAINT MONO (-3215 3110);
DISPLAY INVISIBLE (-3215 3110);
FORCEPROP 1 LAST HDL_POWER P3V3_DB1200
J 1
(-3175 3200);
DISPLAY 0.617021 (-3175 3200);
PAINT GREEN (-3175 3200);
FORCEPROP 1 LAST PATH I43
J 0
(-3175 3175);
DISPLAY 0.872340 (-3175 3175);
PAINT AQUA (-3175 3175);
DISPLAY INVISIBLE (-3175 3175);
FORCEPROP 0 LAST VOLTAGE 5
J 0
(-3225 3150);
PAINT SKYBLUE (-3225 3150);
DISPLAY INVISIBLE (-3225 3150);
FORCEPROP 2 LAST CDS_LIB mstr_symbols
J 0
(-3225 3150);
PAINT ORANGE (-3225 3150);
DISPLAY INVISIBLE (-3225 3150);
FORCEADD GND..1
(-2850 2125);
FORCEPROP 3 LASTPIN (-2850 2175) SIG_NAME GND\g
J 0
(-2840 2185);
DISPLAY 0.659574 (-2840 2185);
PAINT MONO (-2840 2185);
DISPLAY INVISIBLE (-2840 2185);
FORCEPROP 1 LAST SIZE 1B
J 0
(-2775 2075);
DISPLAY 1.127660 (-2775 2075);
PAINT ORANGE (-2775 2075);
DISPLAY INVISIBLE (-2775 2075);
FORCEPROP 2 LAST CDS_LIB mstr_symbols
J 0
(-2850 2125);
PAINT ORANGE (-2850 2125);
DISPLAY INVISIBLE (-2850 2125);
FORCEPROP 1 LAST VOLTAGE 0.0V
J 0
(-2895 2082);
DISPLAY 0.340426 (-2895 2082);
PAINT SKYBLUE (-2895 2082);
DISPLAY INVISIBLE (-2895 2082);
FORCEPROP 2 LAST BOM_COST SYS_CLOCK
J 0
(-3300 2200);
DISPLAY 1.617021 (-3300 2200);
PAINT WHITE (-3300 2200);
DISPLAY INVISIBLE (-3300 2200);
FORCEPROP 2 LAST ROOM DB1200ZL
J 0
(-3175 2200);
DISPLAY 1.127660 (-3175 2200);
PAINT WHITE (-3175 2200);
DISPLAY INVISIBLE (-3175 2200);
FORCEPROP 1 LAST PATH I44
J 0
(-2775 2125);
DISPLAY 0.872340 (-2775 2125);
PAINT AQUA (-2775 2125);
DISPLAY INVISIBLE (-2775 2125);
FORCEPROP 1 LAST BODY_TYPE PLUMBING
J 0
(-2895 2082);
DISPLAY 0.340426 (-2895 2082);
PAINT GREEN (-2895 2082);
DISPLAY INVISIBLE (-2895 2082);
FORCEPROP 1 LAST HDL_POWER GND
J 0
(-2850 2275);
PAINT GREEN (-2850 2275);
DISPLAY INVISIBLE (-2850 2275);
FORCEADD RES..2
(-2675 1425);
FORCEPROP 1 LAST PACK_TYPE 0402
J 0
(-2635 1250);
DISPLAY 0.617021 (-2635 1250);
PAINT SKYBLUE (-2635 1250);
FORCEPROP 1 LAST PART_NUMBER G21796-072
J 0
(-2635 1300);
DISPLAY 0.617021 (-2635 1300);
PAINT BLUE (-2635 1300);
FORCEPROP 1 LAST MATERIAL CHIP
J 0
(-2635 1350);
DISPLAY 0.617021 (-2635 1350);
PAINT SKYBLUE (-2635 1350);
FORCEPROP 1 LAST WATTAGE 1/16W
J 0
(-2635 1400);
DISPLAY 0.617021 (-2635 1400);
PAINT SKYBLUE (-2635 1400);
FORCEPROP 1 LAST TOLERANCE 1%
J 0
(-2630 1450);
DISPLAY 0.617021 (-2630 1450);
PAINT SKYBLUE (-2630 1450);
FORCEPROP 1 LAST VALUE 4.75K
J 0
(-2630 1500);
DISPLAY 0.617021 (-2630 1500);
PAINT SKYBLUE (-2630 1500);
FORCEPROP 1 LAST LOCATION R4D40
J 0
(-2630 1550);
DISPLAY 0.617021 (-2630 1550);
PAINT AQUA (-2630 1550);
FORCEPROP 1 LASTPIN (-2675 1325) $PN 2
J 0
(-2670 1335);
DISPLAY 0.617021 (-2670 1335);
PAINT ORANGE (-2670 1335);
FORCEPROP 1 LASTPIN (-2675 1525) $PN 1
J 0
(-2670 1487);
DISPLAY 0.617021 (-2670 1487);
PAINT ORANGE (-2670 1487);
FORCEPROP 2 LAST CDS_LIB mstr_discrete
J 0
(-2675 1425);
PAINT ORANGE (-2675 1425);
DISPLAY INVISIBLE (-2675 1425);
FORCEPROP 2 LAST ROOM DB1200ZL
J 0
(-2625 1650);
DISPLAY 1.021277 (-2625 1650);
PAINT ORANGE (-2625 1650);
DISPLAY INVISIBLE (-2625 1650);
FORCEPROP 2 LAST CDS_LOCATION R4D40
J 0
(-2630 1550);
DISPLAY 0.617021 (-2630 1550);
PAINT AQUA (-2630 1550);
DISPLAY INVISIBLE (-2630 1550);
FORCEPROP 2 LAST SEC 1
J 0
(-2625 1650);
DISPLAY 0.680851 (-2625 1650);
PAINT MONO (-2625 1650);
DISPLAY INVISIBLE (-2625 1650);
FORCEPROP 2 LAST BOM_COST SYS_CLOCK
J 0
(-2625 1750);
DISPLAY 1.021277 (-2625 1750);
PAINT ORANGE (-2625 1750);
DISPLAY INVISIBLE (-2625 1750);
FORCEPROP 2 LAST SEC_TYPE 0402
J 0
(-2625 1650);
DISPLAY 1.021277 (-2625 1650);
PAINT ORANGE (-2625 1650);
DISPLAY INVISIBLE (-2625 1650);
FORCEPROP 1 LAST PATH I45
J 0
(-2625 1600);
DISPLAY 0.978723 (-2625 1600);
PAINT WHITE (-2625 1600);
DISPLAY INVISIBLE (-2625 1600);
FORCEADD RES..2
(-2675 1025);
FORCEPROP 1 LASTPIN (-2675 1125) $PN 1
J 0
(-2670 1087);
DISPLAY 0.617021 (-2670 1087);
PAINT ORANGE (-2670 1087);
FORCEPROP 1 LASTPIN (-2675 925) $PN 2
J 0
(-2670 935);
DISPLAY 0.617021 (-2670 935);
PAINT ORANGE (-2670 935);
FORCEPROP 1 LAST LOCATION R6P23
J 0
(-2630 1150);
DISPLAY 0.617021 (-2630 1150);
PAINT AQUA (-2630 1150);
FORCEPROP 1 LAST VALUE 4.75K
J 0
(-2630 1100);
DISPLAY 0.617021 (-2630 1100);
PAINT SKYBLUE (-2630 1100);
FORCEPROP 1 LAST TOLERANCE 1%
J 0
(-2630 1050);
DISPLAY 0.617021 (-2630 1050);
PAINT SKYBLUE (-2630 1050);
FORCEPROP 1 LAST WATTAGE 1/16W
J 0
(-2635 1000);
DISPLAY 0.617021 (-2635 1000);
PAINT SKYBLUE (-2635 1000);
FORCEPROP 1 LAST MATERIAL EMPTY
J 0
(-2635 950);
DISPLAY 0.617021 (-2635 950);
PAINT RED (-2635 950);
FORCEPROP 1 LAST PART_NUMBER G21796-072
J 0
(-2635 900);
DISPLAY 0.617021 (-2635 900);
PAINT BLUE (-2635 900);
FORCEPROP 1 LAST PACK_TYPE 0402
J 0
(-2635 850);
DISPLAY 0.617021 (-2635 850);
PAINT SKYBLUE (-2635 850);
FORCEPROP 2 LAST ROOM DB1200ZL
J 0
(-2625 1250);
DISPLAY 1.021277 (-2625 1250);
PAINT ORANGE (-2625 1250);
DISPLAY INVISIBLE (-2625 1250);
FORCEPROP 2 LAST SEC 1
J 0
(-2625 1250);
DISPLAY 0.680851 (-2625 1250);
PAINT MONO (-2625 1250);
DISPLAY INVISIBLE (-2625 1250);
FORCEPROP 2 LAST BOM_COST SYS_CLOCK
J 0
(-2625 1350);
DISPLAY 1.021277 (-2625 1350);
PAINT ORANGE (-2625 1350);
DISPLAY INVISIBLE (-2625 1350);
FORCEPROP 2 LAST SEC_TYPE 0402
J 0
(-2625 1250);
DISPLAY 1.021277 (-2625 1250);
PAINT ORANGE (-2625 1250);
DISPLAY INVISIBLE (-2625 1250);
FORCEPROP 1 LAST PATH I46
J 0
(-2625 1200);
DISPLAY 0.978723 (-2625 1200);
PAINT WHITE (-2625 1200);
DISPLAY INVISIBLE (-2625 1200);
FORCEPROP 2 LAST CDS_LOCATION R6P23
J 0
(-2630 1150);
DISPLAY 0.617021 (-2630 1150);
PAINT AQUA (-2630 1150);
DISPLAY INVISIBLE (-2630 1150);
FORCEPROP 2 LAST CDS_LIB mstr_discrete
J 0
(-2675 1025);
PAINT ORANGE (-2675 1025);
DISPLAY INVISIBLE (-2675 1025);
FORCEADD RES..2
R 2
(-2925 1025);
FORCEPROP 1 LASTPIN (-2925 925) $PN 2
J 2
(-2930 935);
DISPLAY 0.617021 (-2930 935);
PAINT ORANGE (-2930 935);
FORCEPROP 1 LASTPIN (-2925 1125) $PN 1
J 2
(-2930 1087);
DISPLAY 0.617021 (-2930 1087);
PAINT ORANGE (-2930 1087);
FORCEPROP 1 LAST LOCATION R6P22
J 2
(-2970 1150);
DISPLAY 0.617021 (-2970 1150);
PAINT AQUA (-2970 1150);
FORCEPROP 1 LAST VALUE 4.75K
J 2
(-2970 1100);
DISPLAY 0.617021 (-2970 1100);
PAINT SKYBLUE (-2970 1100);
FORCEPROP 1 LAST TOLERANCE 1%
J 2
(-2970 1050);
DISPLAY 0.617021 (-2970 1050);
PAINT SKYBLUE (-2970 1050);
FORCEPROP 1 LAST WATTAGE 1/16W
J 2
(-2965 1000);
DISPLAY 0.617021 (-2965 1000);
PAINT SKYBLUE (-2965 1000);
FORCEPROP 1 LAST MATERIAL EMPTY
J 2
(-2965 950);
DISPLAY 0.617021 (-2965 950);
PAINT RED (-2965 950);
FORCEPROP 1 LAST PART_NUMBER G21796-072
J 2
(-2965 900);
DISPLAY 0.617021 (-2965 900);
PAINT BLUE (-2965 900);
FORCEPROP 1 LAST PACK_TYPE 0402
J 2
(-2965 850);
DISPLAY 0.617021 (-2965 850);
PAINT SKYBLUE (-2965 850);
FORCEPROP 1 LAST PATH I47
J 2
(-2975 1200);
DISPLAY 0.978723 (-2975 1200);
PAINT WHITE (-2975 1200);
DISPLAY INVISIBLE (-2975 1200);
FORCEPROP 2 LAST SEC_TYPE 0402
J 0
(-2975 1250);
DISPLAY 1.021277 (-2975 1250);
PAINT ORANGE (-2975 1250);
DISPLAY INVISIBLE (-2975 1250);
FORCEPROP 2 LAST BOM_COST SYS_CLOCK
J 2
(-2975 1350);
DISPLAY 1.021277 (-2975 1350);
PAINT ORANGE (-2975 1350);
DISPLAY INVISIBLE (-2975 1350);
FORCEPROP 2 LAST SEC 1
J 0
(-2975 1250);
DISPLAY 0.680851 (-2975 1250);
PAINT MONO (-2975 1250);
DISPLAY INVISIBLE (-2975 1250);
FORCEPROP 2 LAST ROOM DB1200ZL
J 2
(-2975 1250);
DISPLAY 1.021277 (-2975 1250);
PAINT ORANGE (-2975 1250);
DISPLAY INVISIBLE (-2975 1250);
FORCEPROP 2 LAST CDS_LIB mstr_discrete
J 0
(-2925 1025);
PAINT MONO (-2925 1025);
DISPLAY INVISIBLE (-2925 1025);
FORCEPROP 2 LAST CDS_LOCATION R6P22
J 2
(-2970 1150);
DISPLAY 0.617021 (-2970 1150);
PAINT AQUA (-2970 1150);
DISPLAY INVISIBLE (-2970 1150);
FORCEADD VCC_CORE..1
(-2925 1800);
FORCEPROP 3 LASTPIN (-2925 1750) SIG_NAME P3V3_DB1200\g
J 0
(-2915 1760);
DISPLAY 0.659574 (-2915 1760);
PAINT MONO (-2915 1760);
DISPLAY INVISIBLE (-2915 1760);
FORCEPROP 1 LAST HDL_POWER P3V3_DB1200
J 1
(-2875 1850);
DISPLAY 0.617021 (-2875 1850);
PAINT GREEN (-2875 1850);
FORCEPROP 0 LAST VOLTAGE 5
J 0
(-2925 1800);
PAINT SKYBLUE (-2925 1800);
DISPLAY INVISIBLE (-2925 1800);
FORCEPROP 2 LAST CDS_LIB mstr_symbols
J 0
(-2925 1800);
PAINT ORANGE (-2925 1800);
DISPLAY INVISIBLE (-2925 1800);
FORCEPROP 1 LAST PATH I49
J 0
(-2875 1825);
DISPLAY 0.872340 (-2875 1825);
PAINT AQUA (-2875 1825);
DISPLAY INVISIBLE (-2875 1825);
FORCEADD OFFPAGE..1
(-1725 2300);
FORCEPROP 2 LAST $XR0 114 
J 0
(-1977 2300);
DISPLAY 0.638298 (-1977 2300);
PAINT MONO (-1977 2300);
FORCEPROP 2 LAST CDS_LIB mstr_standard
J 0
(-1725 2300);
PAINT ORANGE (-1725 2300);
DISPLAY INVISIBLE (-1725 2300);
FORCEPROP 2 LAST PATH I5
J 0
(-1675 2375);
DISPLAY 1.021277 (-1675 2375);
PAINT ORANGE (-1675 2375);
DISPLAY INVISIBLE (-1675 2375);
FORCEPROP 1 LAST OFFPAGE TRUE
J 0
(-1400 2175);
PAINT GREEN (-1400 2175);
DISPLAY INVISIBLE (-1400 2175);
FORCEPROP 1 LAST COMMENT_BODY TRUE
J 0
(-1600 2200);
DISPLAY 1.404255 (-1600 2200);
PAINT PEACH (-1600 2200);
DISPLAY INVISIBLE (-1600 2200);
FORCEADD GND..1
(-2675 700);
FORCEPROP 3 LASTPIN (-2675 750) SIG_NAME GND\g
J 0
(-2665 760);
DISPLAY 0.659574 (-2665 760);
PAINT MONO (-2665 760);
DISPLAY INVISIBLE (-2665 760);
FORCEPROP 1 LAST PATH I50
J 0
(-2600 700);
DISPLAY 0.872340 (-2600 700);
PAINT AQUA (-2600 700);
DISPLAY INVISIBLE (-2600 700);
FORCEPROP 2 LAST CDS_LIB mstr_symbols
J 0
(-2675 700);
PAINT ORANGE (-2675 700);
DISPLAY INVISIBLE (-2675 700);
FORCEPROP 1 LAST SIZE 1B
J 0
(-2600 650);
DISPLAY 1.127660 (-2600 650);
PAINT ORANGE (-2600 650);
DISPLAY INVISIBLE (-2600 650);
FORCEPROP 1 LAST VOLTAGE 0.0V
J 0
(-2720 657);
DISPLAY 0.340426 (-2720 657);
PAINT SKYBLUE (-2720 657);
DISPLAY INVISIBLE (-2720 657);
FORCEPROP 2 LAST ROOM DB1200ZL
J 0
(-3000 775);
DISPLAY 1.127660 (-3000 775);
PAINT WHITE (-3000 775);
DISPLAY INVISIBLE (-3000 775);
FORCEPROP 2 LAST BOM_COST SYS_CLOCK
J 0
(-3125 775);
DISPLAY 1.617021 (-3125 775);
PAINT WHITE (-3125 775);
DISPLAY INVISIBLE (-3125 775);
FORCEPROP 1 LAST BODY_TYPE PLUMBING
J 0
(-2720 657);
DISPLAY 0.340426 (-2720 657);
PAINT GREEN (-2720 657);
DISPLAY INVISIBLE (-2720 657);
FORCEPROP 1 LAST HDL_POWER GND
J 0
(-2675 850);
PAINT GREEN (-2675 850);
DISPLAY INVISIBLE (-2675 850);
FORCEADD OFFPAGE..2
(-1650 1250);
FORCEPROP 2 LAST $XR0 102 
J 0
(-1461 1250);
DISPLAY 0.638298 (-1461 1250);
PAINT MONO (-1461 1250);
FORCEPROP 2 LAST PATH I51
J 0
(-1475 1325);
DISPLAY 1.021277 (-1475 1325);
PAINT ORANGE (-1475 1325);
DISPLAY INVISIBLE (-1475 1325);
FORCEPROP 2 LAST CDS_LIB mstr_standard
J 0
(-1650 1250);
PAINT ORANGE (-1650 1250);
DISPLAY INVISIBLE (-1650 1250);
FORCEPROP 1 LAST OFFPAGE TRUE
J 0
(-1325 1125);
DISPLAY 0.872340 (-1325 1125);
PAINT GREEN (-1325 1125);
DISPLAY INVISIBLE (-1325 1125);
FORCEPROP 1 LAST COMMENT_BODY TRUE
J 0
(-1695 1155);
DISPLAY 0.872340 (-1695 1155);
PAINT GREEN (-1695 1155);
DISPLAY INVISIBLE (-1695 1155);
FORCEADD OFFPAGE..2
(-1650 1200);
FORCEPROP 2 LAST $XR0 102 
J 0
(-1461 1200);
DISPLAY 0.638298 (-1461 1200);
PAINT MONO (-1461 1200);
FORCEPROP 2 LAST PATH I52
J 0
(-1475 1275);
DISPLAY 1.021277 (-1475 1275);
PAINT ORANGE (-1475 1275);
DISPLAY INVISIBLE (-1475 1275);
FORCEPROP 2 LAST CDS_LIB mstr_standard
J 0
(-1650 1200);
PAINT ORANGE (-1650 1200);
DISPLAY INVISIBLE (-1650 1200);
FORCEPROP 1 LAST OFFPAGE TRUE
J 0
(-1325 1075);
DISPLAY 0.872340 (-1325 1075);
PAINT GREEN (-1325 1075);
DISPLAY INVISIBLE (-1325 1075);
FORCEPROP 1 LAST COMMENT_BODY TRUE
J 0
(-1695 1105);
DISPLAY 0.872340 (-1695 1105);
PAINT GREEN (-1695 1105);
DISPLAY INVISIBLE (-1695 1105);
FORCEADD RES..2
R 2
(-2925 1425);
FORCEPROP 1 LASTPIN (-2925 1525) $PN 1
J 2
(-2930 1487);
DISPLAY 0.617021 (-2930 1487);
PAINT ORANGE (-2930 1487);
FORCEPROP 1 LASTPIN (-2925 1325) $PN 2
J 2
(-2930 1335);
DISPLAY 0.617021 (-2930 1335);
PAINT ORANGE (-2930 1335);
FORCEPROP 1 LAST LOCATION R4D41
J 2
(-2970 1550);
DISPLAY 0.617021 (-2970 1550);
PAINT AQUA (-2970 1550);
FORCEPROP 1 LAST VALUE 4.75K
J 2
(-2970 1500);
DISPLAY 0.617021 (-2970 1500);
PAINT SKYBLUE (-2970 1500);
FORCEPROP 1 LAST TOLERANCE 1%
J 2
(-2970 1450);
DISPLAY 0.617021 (-2970 1450);
PAINT SKYBLUE (-2970 1450);
FORCEPROP 1 LAST WATTAGE 1/16W
J 2
(-2965 1400);
DISPLAY 0.617021 (-2965 1400);
PAINT SKYBLUE (-2965 1400);
FORCEPROP 1 LAST MATERIAL CHIP
J 2
(-2965 1350);
DISPLAY 0.617021 (-2965 1350);
PAINT SKYBLUE (-2965 1350);
FORCEPROP 1 LAST PART_NUMBER G21796-072
J 2
(-2965 1300);
DISPLAY 0.617021 (-2965 1300);
PAINT BLUE (-2965 1300);
FORCEPROP 1 LAST PACK_TYPE 0402
J 2
(-2965 1250);
DISPLAY 0.617021 (-2965 1250);
PAINT SKYBLUE (-2965 1250);
FORCEPROP 2 LAST BOM_COST SYS_CLOCK
J 2
(-2975 1750);
DISPLAY 1.021277 (-2975 1750);
PAINT ORANGE (-2975 1750);
DISPLAY INVISIBLE (-2975 1750);
FORCEPROP 2 LAST SEC_TYPE 0402
J 0
(-2975 1650);
DISPLAY 1.021277 (-2975 1650);
PAINT ORANGE (-2975 1650);
DISPLAY INVISIBLE (-2975 1650);
FORCEPROP 2 LAST SEC 1
J 0
(-2975 1650);
DISPLAY 0.680851 (-2975 1650);
PAINT MONO (-2975 1650);
DISPLAY INVISIBLE (-2975 1650);
FORCEPROP 2 LAST CDS_LOCATION R4D41
J 2
(-2970 1550);
DISPLAY 0.617021 (-2970 1550);
PAINT AQUA (-2970 1550);
DISPLAY INVISIBLE (-2970 1550);
FORCEPROP 1 LAST PATH I53
J 2
(-2975 1600);
DISPLAY 0.978723 (-2975 1600);
PAINT WHITE (-2975 1600);
DISPLAY INVISIBLE (-2975 1600);
FORCEPROP 2 LAST ROOM DB1200ZL
J 2
(-2975 1650);
DISPLAY 1.021277 (-2975 1650);
PAINT ORANGE (-2975 1650);
DISPLAY INVISIBLE (-2975 1650);
FORCEPROP 2 LAST CDS_LIB mstr_discrete
J 0
(-2925 1425);
PAINT MONO (-2925 1425);
DISPLAY INVISIBLE (-2925 1425);
FORCEADD OFFPAGE..2
(2025 3600);
FORCEPROP 2 LAST $XR0 103 
J 0
(2214 3600);
DISPLAY 0.638298 (2214 3600);
PAINT MONO (2214 3600);
FORCEPROP 2 LAST PATH I54
J 0
(2200 3675);
DISPLAY 1.021277 (2200 3675);
PAINT ORANGE (2200 3675);
DISPLAY INVISIBLE (2200 3675);
FORCEPROP 2 LAST CDS_LIB mstr_standard
J 0
(2025 3600);
PAINT ORANGE (2025 3600);
DISPLAY INVISIBLE (2025 3600);
FORCEPROP 1 LAST OFFPAGE TRUE
J 0
(2350 3475);
DISPLAY 0.872340 (2350 3475);
PAINT GREEN (2350 3475);
DISPLAY INVISIBLE (2350 3475);
FORCEPROP 1 LAST COMMENT_BODY TRUE
J 0
(1980 3505);
DISPLAY 0.872340 (1980 3505);
PAINT GREEN (1980 3505);
DISPLAY INVISIBLE (1980 3505);
FORCEADD OFFPAGE..2
(2025 3550);
FORCEPROP 2 LAST $XR0 103 
J 0
(2214 3550);
DISPLAY 0.638298 (2214 3550);
PAINT MONO (2214 3550);
FORCEPROP 2 LAST PATH I55
J 0
(2200 3625);
DISPLAY 1.021277 (2200 3625);
PAINT ORANGE (2200 3625);
DISPLAY INVISIBLE (2200 3625);
FORCEPROP 2 LAST CDS_LIB mstr_standard
J 0
(2025 3550);
PAINT ORANGE (2025 3550);
DISPLAY INVISIBLE (2025 3550);
FORCEPROP 1 LAST OFFPAGE TRUE
J 0
(2350 3425);
DISPLAY 0.872340 (2350 3425);
PAINT GREEN (2350 3425);
DISPLAY INVISIBLE (2350 3425);
FORCEPROP 1 LAST COMMENT_BODY TRUE
J 0
(1980 3455);
DISPLAY 0.872340 (1980 3455);
PAINT GREEN (1980 3455);
DISPLAY INVISIBLE (1980 3455);
FORCEADD OFFPAGE..2
(2025 3500);
FORCEPROP 2 LAST $XR0 103 
J 0
(2214 3500);
DISPLAY 0.638298 (2214 3500);
PAINT MONO (2214 3500);
FORCEPROP 2 LAST PATH I56
J 0
(2200 3575);
DISPLAY 1.021277 (2200 3575);
PAINT ORANGE (2200 3575);
DISPLAY INVISIBLE (2200 3575);
FORCEPROP 2 LAST CDS_LIB mstr_standard
J 0
(2025 3500);
PAINT ORANGE (2025 3500);
DISPLAY INVISIBLE (2025 3500);
FORCEPROP 1 LAST OFFPAGE TRUE
J 0
(2350 3375);
DISPLAY 0.872340 (2350 3375);
PAINT GREEN (2350 3375);
DISPLAY INVISIBLE (2350 3375);
FORCEPROP 1 LAST COMMENT_BODY TRUE
J 0
(1980 3405);
DISPLAY 0.872340 (1980 3405);
PAINT GREEN (1980 3405);
DISPLAY INVISIBLE (1980 3405);
FORCEADD OFFPAGE..2
(2025 3450);
FORCEPROP 2 LAST $XR0 103 
J 0
(2214 3450);
DISPLAY 0.638298 (2214 3450);
PAINT MONO (2214 3450);
FORCEPROP 2 LAST PATH I57
J 0
(2200 3525);
DISPLAY 1.021277 (2200 3525);
PAINT ORANGE (2200 3525);
DISPLAY INVISIBLE (2200 3525);
FORCEPROP 2 LAST CDS_LIB mstr_standard
J 0
(2025 3450);
PAINT ORANGE (2025 3450);
DISPLAY INVISIBLE (2025 3450);
FORCEPROP 1 LAST OFFPAGE TRUE
J 0
(2350 3325);
DISPLAY 0.872340 (2350 3325);
PAINT GREEN (2350 3325);
DISPLAY INVISIBLE (2350 3325);
FORCEPROP 1 LAST COMMENT_BODY TRUE
J 0
(1980 3355);
DISPLAY 0.872340 (1980 3355);
PAINT GREEN (1980 3355);
DISPLAY INVISIBLE (1980 3355);
FORCEADD OFFPAGE..2
(2025 3400);
FORCEPROP 2 LAST $XR0 103 
J 0
(2214 3400);
DISPLAY 0.638298 (2214 3400);
PAINT MONO (2214 3400);
FORCEPROP 2 LAST PATH I58
J 0
(2200 3475);
DISPLAY 1.021277 (2200 3475);
PAINT ORANGE (2200 3475);
DISPLAY INVISIBLE (2200 3475);
FORCEPROP 2 LAST CDS_LIB mstr_standard
J 0
(2025 3400);
PAINT ORANGE (2025 3400);
DISPLAY INVISIBLE (2025 3400);
FORCEPROP 1 LAST OFFPAGE TRUE
J 0
(2350 3275);
DISPLAY 0.872340 (2350 3275);
PAINT GREEN (2350 3275);
DISPLAY INVISIBLE (2350 3275);
FORCEPROP 1 LAST COMMENT_BODY TRUE
J 0
(1980 3305);
DISPLAY 0.872340 (1980 3305);
PAINT GREEN (1980 3305);
DISPLAY INVISIBLE (1980 3305);
FORCEADD OFFPAGE..2
(2025 3350);
FORCEPROP 2 LAST $XR0 103 
J 0
(2214 3350);
DISPLAY 0.638298 (2214 3350);
PAINT MONO (2214 3350);
FORCEPROP 2 LAST PATH I59
J 0
(2200 3425);
DISPLAY 1.021277 (2200 3425);
PAINT ORANGE (2200 3425);
DISPLAY INVISIBLE (2200 3425);
FORCEPROP 2 LAST CDS_LIB mstr_standard
J 0
(2025 3350);
PAINT ORANGE (2025 3350);
DISPLAY INVISIBLE (2025 3350);
FORCEPROP 1 LAST OFFPAGE TRUE
J 0
(2350 3225);
DISPLAY 0.872340 (2350 3225);
PAINT GREEN (2350 3225);
DISPLAY INVISIBLE (2350 3225);
FORCEPROP 1 LAST COMMENT_BODY TRUE
J 0
(1980 3255);
DISPLAY 0.872340 (1980 3255);
PAINT GREEN (1980 3255);
DISPLAY INVISIBLE (1980 3255);
FORCEADD GND..1
(1425 1725);
FORCEPROP 3 LASTPIN (1425 1775) SIG_NAME GND\g
J 0
(1435 1785);
DISPLAY 0.659574 (1435 1785);
PAINT MONO (1435 1785);
DISPLAY INVISIBLE (1435 1785);
FORCEPROP 2 LAST CDS_LIB mstr_symbols
J 0
(1425 1725);
PAINT ORANGE (1425 1725);
DISPLAY INVISIBLE (1425 1725);
FORCEPROP 1 LAST PATH I6
J 0
(1500 1725);
DISPLAY 0.872340 (1500 1725);
PAINT AQUA (1500 1725);
DISPLAY INVISIBLE (1500 1725);
FORCEPROP 1 LAST SIZE 1B
J 0
(1500 1675);
DISPLAY 1.127660 (1500 1675);
PAINT ORANGE (1500 1675);
DISPLAY INVISIBLE (1500 1675);
FORCEPROP 1 LAST VOLTAGE 0.0V
J 0
(1380 1682);
DISPLAY 0.340426 (1380 1682);
PAINT SKYBLUE (1380 1682);
DISPLAY INVISIBLE (1380 1682);
FORCEPROP 2 LAST ROOM DB1200ZL
J 0
(1100 1800);
DISPLAY 1.127660 (1100 1800);
PAINT WHITE (1100 1800);
DISPLAY INVISIBLE (1100 1800);
FORCEPROP 2 LAST BOM_COST SYS_CLOCK
J 0
(975 1800);
DISPLAY 1.617021 (975 1800);
PAINT WHITE (975 1800);
DISPLAY INVISIBLE (975 1800);
FORCEPROP 1 LAST BODY_TYPE PLUMBING
J 0
(1380 1682);
DISPLAY 0.340426 (1380 1682);
PAINT GREEN (1380 1682);
DISPLAY INVISIBLE (1380 1682);
FORCEPROP 1 LAST HDL_POWER GND
J 0
(1425 1875);
PAINT GREEN (1425 1875);
DISPLAY INVISIBLE (1425 1875);
FORCEADD OFFPAGE..2
(2025 3300);
FORCEPROP 2 LAST $XR0 103 
J 0
(2214 3300);
DISPLAY 0.638298 (2214 3300);
PAINT MONO (2214 3300);
FORCEPROP 2 LAST PATH I60
J 0
(2200 3375);
DISPLAY 1.021277 (2200 3375);
PAINT ORANGE (2200 3375);
DISPLAY INVISIBLE (2200 3375);
FORCEPROP 2 LAST CDS_LIB mstr_standard
J 0
(2025 3300);
PAINT ORANGE (2025 3300);
DISPLAY INVISIBLE (2025 3300);
FORCEPROP 1 LAST OFFPAGE TRUE
J 0
(2350 3175);
DISPLAY 0.872340 (2350 3175);
PAINT GREEN (2350 3175);
DISPLAY INVISIBLE (2350 3175);
FORCEPROP 1 LAST COMMENT_BODY TRUE
J 0
(1980 3205);
DISPLAY 0.872340 (1980 3205);
PAINT GREEN (1980 3205);
DISPLAY INVISIBLE (1980 3205);
FORCEADD OFFPAGE..2
(2025 3250);
FORCEPROP 2 LAST $XR0 103 
J 0
(2214 3250);
DISPLAY 0.638298 (2214 3250);
PAINT MONO (2214 3250);
FORCEPROP 2 LAST PATH I61
J 0
(2200 3325);
DISPLAY 1.021277 (2200 3325);
PAINT ORANGE (2200 3325);
DISPLAY INVISIBLE (2200 3325);
FORCEPROP 2 LAST CDS_LIB mstr_standard
J 0
(2025 3250);
PAINT ORANGE (2025 3250);
DISPLAY INVISIBLE (2025 3250);
FORCEPROP 1 LAST OFFPAGE TRUE
J 0
(2350 3125);
DISPLAY 0.872340 (2350 3125);
PAINT GREEN (2350 3125);
DISPLAY INVISIBLE (2350 3125);
FORCEPROP 1 LAST COMMENT_BODY TRUE
J 0
(1980 3155);
DISPLAY 0.872340 (1980 3155);
PAINT GREEN (1980 3155);
DISPLAY INVISIBLE (1980 3155);
FORCEADD OFFPAGE..2
(2025 3200);
FORCEPROP 2 LAST $XR0 103 
J 0
(2214 3200);
DISPLAY 0.638298 (2214 3200);
PAINT MONO (2214 3200);
FORCEPROP 2 LAST PATH I62
J 0
(2200 3275);
DISPLAY 1.021277 (2200 3275);
PAINT ORANGE (2200 3275);
DISPLAY INVISIBLE (2200 3275);
FORCEPROP 2 LAST CDS_LIB mstr_standard
J 0
(2025 3200);
PAINT ORANGE (2025 3200);
DISPLAY INVISIBLE (2025 3200);
FORCEPROP 1 LAST OFFPAGE TRUE
J 0
(2350 3075);
DISPLAY 0.872340 (2350 3075);
PAINT GREEN (2350 3075);
DISPLAY INVISIBLE (2350 3075);
FORCEPROP 1 LAST COMMENT_BODY TRUE
J 0
(1980 3105);
DISPLAY 0.872340 (1980 3105);
PAINT GREEN (1980 3105);
DISPLAY INVISIBLE (1980 3105);
FORCEADD OFFPAGE..2
(2025 3150);
FORCEPROP 2 LAST $XR0 103 
J 0
(2214 3150);
DISPLAY 0.638298 (2214 3150);
PAINT MONO (2214 3150);
FORCEPROP 2 LAST PATH I63
J 0
(2200 3225);
DISPLAY 1.021277 (2200 3225);
PAINT ORANGE (2200 3225);
DISPLAY INVISIBLE (2200 3225);
FORCEPROP 2 LAST CDS_LIB mstr_standard
J 0
(2025 3150);
PAINT ORANGE (2025 3150);
DISPLAY INVISIBLE (2025 3150);
FORCEPROP 1 LAST OFFPAGE TRUE
J 0
(2350 3025);
DISPLAY 0.872340 (2350 3025);
PAINT GREEN (2350 3025);
DISPLAY INVISIBLE (2350 3025);
FORCEPROP 1 LAST COMMENT_BODY TRUE
J 0
(1980 3055);
DISPLAY 0.872340 (1980 3055);
PAINT GREEN (1980 3055);
DISPLAY INVISIBLE (1980 3055);
FORCEADD OFFPAGE..2
(2025 3100);
FORCEPROP 2 LAST $XR0 103 
J 0
(2214 3100);
DISPLAY 0.638298 (2214 3100);
PAINT MONO (2214 3100);
FORCEPROP 2 LAST PATH I64
J 0
(2200 3175);
DISPLAY 1.021277 (2200 3175);
PAINT ORANGE (2200 3175);
DISPLAY INVISIBLE (2200 3175);
FORCEPROP 2 LAST CDS_LIB mstr_standard
J 0
(2025 3100);
PAINT ORANGE (2025 3100);
DISPLAY INVISIBLE (2025 3100);
FORCEPROP 1 LAST OFFPAGE TRUE
J 0
(2350 2975);
DISPLAY 0.872340 (2350 2975);
PAINT GREEN (2350 2975);
DISPLAY INVISIBLE (2350 2975);
FORCEPROP 1 LAST COMMENT_BODY TRUE
J 0
(1980 3005);
DISPLAY 0.872340 (1980 3005);
PAINT GREEN (1980 3005);
DISPLAY INVISIBLE (1980 3005);
FORCEADD OFFPAGE..2
(2025 3050);
FORCEPROP 2 LAST $XR0 103 
J 0
(2214 3050);
DISPLAY 0.638298 (2214 3050);
PAINT MONO (2214 3050);
FORCEPROP 2 LAST PATH I65
J 0
(2200 3125);
DISPLAY 1.021277 (2200 3125);
PAINT ORANGE (2200 3125);
DISPLAY INVISIBLE (2200 3125);
FORCEPROP 2 LAST CDS_LIB mstr_standard
J 0
(2025 3050);
PAINT ORANGE (2025 3050);
DISPLAY INVISIBLE (2025 3050);
FORCEPROP 1 LAST OFFPAGE TRUE
J 0
(2350 2925);
DISPLAY 0.872340 (2350 2925);
PAINT GREEN (2350 2925);
DISPLAY INVISIBLE (2350 2925);
FORCEPROP 1 LAST COMMENT_BODY TRUE
J 0
(1980 2955);
DISPLAY 0.872340 (1980 2955);
PAINT GREEN (1980 2955);
DISPLAY INVISIBLE (1980 2955);
FORCEADD OFFPAGE..2
(2025 3000);
FORCEPROP 2 LAST $XR0 103 
J 0
(2214 3000);
DISPLAY 0.638298 (2214 3000);
PAINT MONO (2214 3000);
FORCEPROP 2 LAST PATH I66
J 0
(2200 3075);
DISPLAY 1.021277 (2200 3075);
PAINT ORANGE (2200 3075);
DISPLAY INVISIBLE (2200 3075);
FORCEPROP 2 LAST CDS_LIB mstr_standard
J 0
(2025 3000);
PAINT ORANGE (2025 3000);
DISPLAY INVISIBLE (2025 3000);
FORCEPROP 1 LAST OFFPAGE TRUE
J 0
(2350 2875);
DISPLAY 0.872340 (2350 2875);
PAINT GREEN (2350 2875);
DISPLAY INVISIBLE (2350 2875);
FORCEPROP 1 LAST COMMENT_BODY TRUE
J 0
(1980 2905);
DISPLAY 0.872340 (1980 2905);
PAINT GREEN (1980 2905);
DISPLAY INVISIBLE (1980 2905);
FORCEADD OFFPAGE..2
(2025 2950);
FORCEPROP 2 LAST $XR0 103 
J 0
(2214 2950);
DISPLAY 0.638298 (2214 2950);
PAINT MONO (2214 2950);
FORCEPROP 2 LAST PATH I67
J 0
(2200 3025);
DISPLAY 1.021277 (2200 3025);
PAINT ORANGE (2200 3025);
DISPLAY INVISIBLE (2200 3025);
FORCEPROP 2 LAST CDS_LIB mstr_standard
J 0
(2025 2950);
PAINT ORANGE (2025 2950);
DISPLAY INVISIBLE (2025 2950);
FORCEPROP 1 LAST OFFPAGE TRUE
J 0
(2350 2825);
DISPLAY 0.872340 (2350 2825);
PAINT GREEN (2350 2825);
DISPLAY INVISIBLE (2350 2825);
FORCEPROP 1 LAST COMMENT_BODY TRUE
J 0
(1980 2855);
DISPLAY 0.872340 (1980 2855);
PAINT GREEN (1980 2855);
DISPLAY INVISIBLE (1980 2855);
FORCEADD OFFPAGE..2
(2025 2900);
FORCEPROP 2 LAST $XR0 103 
J 0
(2214 2900);
DISPLAY 0.638298 (2214 2900);
PAINT MONO (2214 2900);
FORCEPROP 2 LAST PATH I68
J 0
(2200 2975);
DISPLAY 1.021277 (2200 2975);
PAINT ORANGE (2200 2975);
DISPLAY INVISIBLE (2200 2975);
FORCEPROP 2 LAST CDS_LIB mstr_standard
J 0
(2025 2900);
PAINT ORANGE (2025 2900);
DISPLAY INVISIBLE (2025 2900);
FORCEPROP 1 LAST OFFPAGE TRUE
J 0
(2350 2775);
DISPLAY 0.872340 (2350 2775);
PAINT GREEN (2350 2775);
DISPLAY INVISIBLE (2350 2775);
FORCEPROP 1 LAST COMMENT_BODY TRUE
J 0
(1980 2805);
DISPLAY 0.872340 (1980 2805);
PAINT GREEN (1980 2805);
DISPLAY INVISIBLE (1980 2805);
FORCEADD OFFPAGE..2
(2025 2850);
FORCEPROP 2 LAST $XR0 103 
J 0
(2214 2850);
DISPLAY 0.638298 (2214 2850);
PAINT MONO (2214 2850);
FORCEPROP 2 LAST PATH I69
J 0
(2200 2925);
DISPLAY 1.021277 (2200 2925);
PAINT ORANGE (2200 2925);
DISPLAY INVISIBLE (2200 2925);
FORCEPROP 2 LAST CDS_LIB mstr_standard
J 0
(2025 2850);
PAINT ORANGE (2025 2850);
DISPLAY INVISIBLE (2025 2850);
FORCEPROP 1 LAST OFFPAGE TRUE
J 0
(2350 2725);
DISPLAY 0.872340 (2350 2725);
PAINT GREEN (2350 2725);
DISPLAY INVISIBLE (2350 2725);
FORCEPROP 1 LAST COMMENT_BODY TRUE
J 0
(1980 2755);
DISPLAY 0.872340 (1980 2755);
PAINT GREEN (1980 2755);
DISPLAY INVISIBLE (1980 2755);
FORCEADD OFFPAGE..2
(2025 2800);
FORCEPROP 2 LAST $XR0 103 
J 0
(2214 2800);
DISPLAY 0.638298 (2214 2800);
PAINT MONO (2214 2800);
FORCEPROP 2 LAST PATH I70
J 0
(2200 2875);
DISPLAY 1.021277 (2200 2875);
PAINT ORANGE (2200 2875);
DISPLAY INVISIBLE (2200 2875);
FORCEPROP 2 LAST CDS_LIB mstr_standard
J 0
(2025 2800);
PAINT ORANGE (2025 2800);
DISPLAY INVISIBLE (2025 2800);
FORCEPROP 1 LAST OFFPAGE TRUE
J 0
(2350 2675);
DISPLAY 0.872340 (2350 2675);
PAINT GREEN (2350 2675);
DISPLAY INVISIBLE (2350 2675);
FORCEPROP 1 LAST COMMENT_BODY TRUE
J 0
(1980 2705);
DISPLAY 0.872340 (1980 2705);
PAINT GREEN (1980 2705);
DISPLAY INVISIBLE (1980 2705);
FORCEADD OFFPAGE..2
(2025 2750);
FORCEPROP 2 LAST $XR0 103 
J 0
(2214 2750);
DISPLAY 0.638298 (2214 2750);
PAINT MONO (2214 2750);
FORCEPROP 2 LAST PATH I71
J 0
(2200 2825);
DISPLAY 1.021277 (2200 2825);
PAINT ORANGE (2200 2825);
DISPLAY INVISIBLE (2200 2825);
FORCEPROP 2 LAST CDS_LIB mstr_standard
J 0
(2025 2750);
PAINT ORANGE (2025 2750);
DISPLAY INVISIBLE (2025 2750);
FORCEPROP 1 LAST OFFPAGE TRUE
J 0
(2350 2625);
DISPLAY 0.872340 (2350 2625);
PAINT GREEN (2350 2625);
DISPLAY INVISIBLE (2350 2625);
FORCEPROP 1 LAST COMMENT_BODY TRUE
J 0
(1980 2655);
DISPLAY 0.872340 (1980 2655);
PAINT GREEN (1980 2655);
DISPLAY INVISIBLE (1980 2655);
FORCEADD OFFPAGE..2
(2025 2700);
FORCEPROP 2 LAST $XR0 103 
J 0
(2214 2700);
DISPLAY 0.638298 (2214 2700);
PAINT MONO (2214 2700);
FORCEPROP 2 LAST PATH I72
J 0
(2200 2775);
DISPLAY 1.021277 (2200 2775);
PAINT ORANGE (2200 2775);
DISPLAY INVISIBLE (2200 2775);
FORCEPROP 2 LAST CDS_LIB mstr_standard
J 0
(2025 2700);
PAINT ORANGE (2025 2700);
DISPLAY INVISIBLE (2025 2700);
FORCEPROP 1 LAST OFFPAGE TRUE
J 0
(2350 2575);
DISPLAY 0.872340 (2350 2575);
PAINT GREEN (2350 2575);
DISPLAY INVISIBLE (2350 2575);
FORCEPROP 1 LAST COMMENT_BODY TRUE
J 0
(1980 2605);
DISPLAY 0.872340 (1980 2605);
PAINT GREEN (1980 2605);
DISPLAY INVISIBLE (1980 2605);
FORCEADD OFFPAGE..2
(2025 2650);
FORCEPROP 2 LAST $XR0 103 
J 0
(2214 2650);
DISPLAY 0.638298 (2214 2650);
PAINT MONO (2214 2650);
FORCEPROP 2 LAST PATH I73
J 0
(2200 2725);
DISPLAY 1.021277 (2200 2725);
PAINT ORANGE (2200 2725);
DISPLAY INVISIBLE (2200 2725);
FORCEPROP 2 LAST CDS_LIB mstr_standard
J 0
(2025 2650);
PAINT ORANGE (2025 2650);
DISPLAY INVISIBLE (2025 2650);
FORCEPROP 1 LAST OFFPAGE TRUE
J 0
(2350 2525);
DISPLAY 0.872340 (2350 2525);
PAINT GREEN (2350 2525);
DISPLAY INVISIBLE (2350 2525);
FORCEPROP 1 LAST COMMENT_BODY TRUE
J 0
(1980 2555);
DISPLAY 0.872340 (1980 2555);
PAINT GREEN (1980 2555);
DISPLAY INVISIBLE (1980 2555);
FORCEADD OFFPAGE..2
(2025 2600);
FORCEPROP 2 LAST $XR0 103 
J 0
(2214 2600);
DISPLAY 0.638298 (2214 2600);
PAINT MONO (2214 2600);
FORCEPROP 2 LAST PATH I74
J 0
(2200 2675);
DISPLAY 1.021277 (2200 2675);
PAINT ORANGE (2200 2675);
DISPLAY INVISIBLE (2200 2675);
FORCEPROP 2 LAST CDS_LIB mstr_standard
J 0
(2025 2600);
PAINT ORANGE (2025 2600);
DISPLAY INVISIBLE (2025 2600);
FORCEPROP 1 LAST OFFPAGE TRUE
J 0
(2350 2475);
DISPLAY 0.872340 (2350 2475);
PAINT GREEN (2350 2475);
DISPLAY INVISIBLE (2350 2475);
FORCEPROP 1 LAST COMMENT_BODY TRUE
J 0
(1980 2505);
DISPLAY 0.872340 (1980 2505);
PAINT GREEN (1980 2505);
DISPLAY INVISIBLE (1980 2505);
FORCEADD OFFPAGE..2
(2025 2550);
FORCEPROP 2 LAST $XR0 103 
J 0
(2214 2550);
DISPLAY 0.638298 (2214 2550);
PAINT MONO (2214 2550);
FORCEPROP 2 LAST PATH I75
J 0
(2200 2625);
DISPLAY 1.021277 (2200 2625);
PAINT ORANGE (2200 2625);
DISPLAY INVISIBLE (2200 2625);
FORCEPROP 2 LAST CDS_LIB mstr_standard
J 0
(2025 2550);
PAINT ORANGE (2025 2550);
DISPLAY INVISIBLE (2025 2550);
FORCEPROP 1 LAST OFFPAGE TRUE
J 0
(2350 2425);
DISPLAY 0.872340 (2350 2425);
PAINT GREEN (2350 2425);
DISPLAY INVISIBLE (2350 2425);
FORCEPROP 1 LAST COMMENT_BODY TRUE
J 0
(1980 2455);
DISPLAY 0.872340 (1980 2455);
PAINT GREEN (1980 2455);
DISPLAY INVISIBLE (1980 2455);
FORCEADD OFFPAGE..2
(2025 2500);
FORCEPROP 2 LAST $XR0 103 
J 0
(2214 2500);
DISPLAY 0.638298 (2214 2500);
PAINT MONO (2214 2500);
FORCEPROP 2 LAST PATH I76
J 0
(2200 2575);
DISPLAY 1.021277 (2200 2575);
PAINT ORANGE (2200 2575);
DISPLAY INVISIBLE (2200 2575);
FORCEPROP 2 LAST CDS_LIB mstr_standard
J 0
(2025 2500);
PAINT ORANGE (2025 2500);
DISPLAY INVISIBLE (2025 2500);
FORCEPROP 1 LAST OFFPAGE TRUE
J 0
(2350 2375);
DISPLAY 0.872340 (2350 2375);
PAINT GREEN (2350 2375);
DISPLAY INVISIBLE (2350 2375);
FORCEPROP 1 LAST COMMENT_BODY TRUE
J 0
(1980 2405);
DISPLAY 0.872340 (1980 2405);
PAINT GREEN (1980 2405);
DISPLAY INVISIBLE (1980 2405);
FORCEADD OFFPAGE..2
(2025 2450);
FORCEPROP 2 LAST $XR0 103 
J 0
(2214 2450);
DISPLAY 0.638298 (2214 2450);
PAINT MONO (2214 2450);
FORCEPROP 2 LAST PATH I77
J 0
(2200 2525);
DISPLAY 1.021277 (2200 2525);
PAINT ORANGE (2200 2525);
DISPLAY INVISIBLE (2200 2525);
FORCEPROP 2 LAST CDS_LIB mstr_standard
J 0
(2025 2450);
PAINT ORANGE (2025 2450);
DISPLAY INVISIBLE (2025 2450);
FORCEPROP 1 LAST OFFPAGE TRUE
J 0
(2350 2325);
DISPLAY 0.872340 (2350 2325);
PAINT GREEN (2350 2325);
DISPLAY INVISIBLE (2350 2325);
FORCEPROP 1 LAST COMMENT_BODY TRUE
J 0
(1980 2355);
DISPLAY 0.872340 (1980 2355);
PAINT GREEN (1980 2355);
DISPLAY INVISIBLE (1980 2355);
FORCEADD CAP_A..1
(2275 900);
FORCEPROP 1 LASTPIN (2275 1000) $PN 1
J 0
(2285 980);
DISPLAY 0.617021 (2285 980);
PAINT ORANGE (2285 980);
FORCEPROP 1 LAST PART_NUMBER A36096-030
J 0
(2325 750);
DISPLAY 0.617021 (2325 750);
PAINT BLUE (2325 750);
FORCEPROP 1 LAST VOLTAGE 16V
J 0
(2325 900);
DISPLAY 0.617021 (2325 900);
PAINT SKYBLUE (2325 900);
FORCEPROP 1 LAST MATERIAL X7R
J 0
(2325 800);
DISPLAY 0.617021 (2325 800);
PAINT SKYBLUE (2325 800);
FORCEPROP 1 LAST TOLERANCE 10%
J 0
(2325 850);
DISPLAY 0.617021 (2325 850);
PAINT SKYBLUE (2325 850);
FORCEPROP 1 LAST PACK_TYPE 0402V
J 0
(2325 700);
DISPLAY 0.617021 (2325 700);
PAINT SKYBLUE (2325 700);
FORCEPROP 1 LASTPIN (2275 800) $PN 2
J 0
(2285 780);
DISPLAY 0.617021 (2285 780);
PAINT ORANGE (2285 780);
FORCEPROP 1 LAST LOCATION C6P9
J 0
(2325 1000);
DISPLAY 0.617021 (2325 1000);
PAINT AQUA (2325 1000);
FORCEPROP 1 LAST VALUE 0.1UF
J 0
(2325 950);
DISPLAY 0.617021 (2325 950);
PAINT SKYBLUE (2325 950);
FORCEPROP 2 LAST CDS_SEC 1
J 0
(2325 1050);
PAINT ORANGE (2325 1050);
DISPLAY INVISIBLE (2325 1050);
FORCEPROP 2 LAST BOM_COST SYS_CLOCK
J 0
(2325 1200);
DISPLAY 1.021277 (2325 1200);
PAINT ORANGE (2325 1200);
DISPLAY INVISIBLE (2325 1200);
FORCEPROP 2 LAST CDS_LOCATION C6P9
J 0
(2325 1000);
DISPLAY 0.617021 (2325 1000);
PAINT AQUA (2325 1000);
DISPLAY INVISIBLE (2325 1000);
FORCEPROP 2 LAST SEC 1
J 0
(2325 1100);
DISPLAY 0.680851 (2325 1100);
PAINT MONO (2325 1100);
DISPLAY INVISIBLE (2325 1100);
FORCEPROP 2 LAST ROOM DB1200ZL
J 0
(2325 1100);
DISPLAY 1.021277 (2325 1100);
PAINT ORANGE (2325 1100);
DISPLAY INVISIBLE (2325 1100);
FORCEPROP 1 LAST PATH I79
J 0
(2325 1050);
DISPLAY 0.978723 (2325 1050);
PAINT WHITE (2325 1050);
DISPLAY INVISIBLE (2325 1050);
FORCEPROP 2 LAST SEC_TYPE 0402V
J 0
(2325 1100);
DISPLAY 1.021277 (2325 1100);
PAINT ORANGE (2325 1100);
DISPLAY INVISIBLE (2325 1100);
FORCEPROP 2 LAST CDS_LIB dev_discrete
J 0
(2275 900);
PAINT ORANGE (2275 900);
DISPLAY INVISIBLE (2275 900);
FORCEADD FERRITE..1
(1700 1125);
FORCEPROP 1 LAST MATERIAL FB
J 0
(1755 1025);
DISPLAY 0.617021 (1755 1025);
PAINT SKYBLUE (1755 1025);
FORCEPROP 1 LAST PACK_TYPE SMLF
J 0
(1605 975);
DISPLAY 0.617021 (1605 975);
PAINT SKYBLUE (1605 975);
FORCEPROP 1 LAST VALUE 600
J 2
(1705 1025);
DISPLAY 0.617021 (1705 1025);
PAINT SKYBLUE (1705 1025);
FORCEPROP 1 LASTPIN (1600 1125) $PN 1
J 2
(1635 1135);
DISPLAY 0.617021 (1635 1135);
PAINT WHITE (1635 1135);
FORCEPROP 1 LAST PART_NUMBER 656554-043
J 0
(1605 1240);
DISPLAY 0.617021 (1605 1240);
PAINT BLUE (1605 1240);
FORCEPROP 1 LAST LOCATION FB6P1
J 0
(1605 1180);
DISPLAY 0.617021 (1605 1180);
PAINT AQUA (1605 1180);
FORCEPROP 1 LASTPIN (1800 1125) $PN 2
J 0
(1780 1135);
DISPLAY 0.617021 (1780 1135);
PAINT WHITE (1780 1135);
FORCEPROP 2 LAST ROOM DB1200ZL
J 0
(1625 1325);
DISPLAY 1.021277 (1625 1325);
PAINT ORANGE (1625 1325);
DISPLAY INVISIBLE (1625 1325);
FORCEPROP 1 LAST PATH I8
J 0
(1605 1290);
DISPLAY 0.872340 (1605 1290);
PAINT PURPLE (1605 1290);
DISPLAY INVISIBLE (1605 1290);
FORCEPROP 2 LAST SEC 1
J 0
(1625 1350);
DISPLAY 0.680851 (1625 1350);
PAINT MONO (1625 1350);
DISPLAY INVISIBLE (1625 1350);
FORCEPROP 2 LAST SEC_TYPE SMLF
J 0
(1625 1350);
DISPLAY 1.021277 (1625 1350);
PAINT ORANGE (1625 1350);
DISPLAY INVISIBLE (1625 1350);
FORCEPROP 2 LAST BOM_COST SYS_CLOCK
J 0
(1625 1325);
DISPLAY 1.021277 (1625 1325);
PAINT ORANGE (1625 1325);
DISPLAY INVISIBLE (1625 1325);
FORCEPROP 2 LAST CDS_LOCATION FB6P1
J 0
(1605 1180);
DISPLAY 0.617021 (1605 1180);
PAINT AQUA (1605 1180);
DISPLAY INVISIBLE (1605 1180);
FORCEPROP 2 LAST CDS_LIB mstr_discrete
J 0
(1700 1125);
PAINT ORANGE (1700 1125);
DISPLAY INVISIBLE (1700 1125);
FORCEADD RES..2
(-3225 2475);
FORCEPROP 1 LASTPIN (-3225 2575) $PN 1
J 0
(-3220 2537);
DISPLAY 0.617021 (-3220 2537);
PAINT ORANGE (-3220 2537);
FORCEPROP 1 LASTPIN (-3225 2375) $PN 2
J 0
(-3220 2385);
DISPLAY 0.617021 (-3220 2385);
PAINT ORANGE (-3220 2385);
FORCEPROP 1 LAST LOCATION R6P21
J 0
(-3180 2600);
DISPLAY 0.617021 (-3180 2600);
PAINT AQUA (-3180 2600);
FORCEPROP 1 LAST VALUE 1.00K
J 0
(-3180 2550);
DISPLAY 0.617021 (-3180 2550);
PAINT SKYBLUE (-3180 2550);
FORCEPROP 1 LAST TOLERANCE 1%
J 0
(-3180 2500);
DISPLAY 0.617021 (-3180 2500);
PAINT SKYBLUE (-3180 2500);
FORCEPROP 1 LAST WATTAGE 1/16W
J 0
(-3185 2450);
DISPLAY 0.617021 (-3185 2450);
PAINT SKYBLUE (-3185 2450);
FORCEPROP 1 LAST MATERIAL CHIP
J 0
(-3185 2400);
DISPLAY 0.617021 (-3185 2400);
PAINT SKYBLUE (-3185 2400);
FORCEPROP 1 LAST PACK_TYPE 0402
J 0
(-3185 2300);
DISPLAY 0.617021 (-3185 2300);
PAINT SKYBLUE (-3185 2300);
FORCEPROP 1 LAST PART_NUMBER G21796-026
J 0
(-3185 2350);
DISPLAY 0.617021 (-3185 2350);
PAINT BLUE (-3185 2350);
FORCEPROP 2 LAST SEC_TYPE 0402
J 0
(-3175 2700);
DISPLAY 1.021277 (-3175 2700);
PAINT ORANGE (-3175 2700);
DISPLAY INVISIBLE (-3175 2700);
FORCEPROP 2 LAST ROOM DB1200ZL
J 0
(-3175 2650);
DISPLAY 1.361702 (-3175 2650);
PAINT ORANGE (-3175 2650);
DISPLAY INVISIBLE (-3175 2650);
FORCEPROP 1 LAST PATH I80
J 0
(-3175 2650);
DISPLAY 0.978723 (-3175 2650);
PAINT WHITE (-3175 2650);
DISPLAY INVISIBLE (-3175 2650);
FORCEPROP 2 LAST CDS_LOCATION R6P21
J 0
(-3180 2600);
DISPLAY 0.617021 (-3180 2600);
PAINT AQUA (-3180 2600);
DISPLAY INVISIBLE (-3180 2600);
FORCEPROP 2 LAST SEC 1
J 0
(-3175 2700);
DISPLAY 0.680851 (-3175 2700);
PAINT MONO (-3175 2700);
DISPLAY INVISIBLE (-3175 2700);
FORCEPROP 2 LAST BOM_COST SYS_CLOCK
J 0
(-3175 2650);
DISPLAY 1.361702 (-3175 2650);
PAINT ORANGE (-3175 2650);
DISPLAY INVISIBLE (-3175 2650);
FORCEPROP 2 LAST CDS_LIB mstr_discrete
J 0
(-3225 2475);
PAINT ORANGE (-3225 2475);
DISPLAY INVISIBLE (-3225 2475);
FORCEADD RES..2
(-2850 2475);
FORCEPROP 1 LASTPIN (-2850 2375) $PN 2
J 0
(-2845 2385);
DISPLAY 0.617021 (-2845 2385);
PAINT ORANGE (-2845 2385);
FORCEPROP 1 LAST LOCATION R6P20
J 0
(-2805 2600);
DISPLAY 0.617021 (-2805 2600);
PAINT AQUA (-2805 2600);
FORCEPROP 1 LASTPIN (-2850 2575) $PN 1
J 0
(-2845 2537);
DISPLAY 0.617021 (-2845 2537);
PAINT ORANGE (-2845 2537);
FORCEPROP 1 LAST VALUE 1.00K
J 0
(-2805 2550);
DISPLAY 0.617021 (-2805 2550);
PAINT SKYBLUE (-2805 2550);
FORCEPROP 1 LAST TOLERANCE 1%
J 0
(-2805 2500);
DISPLAY 0.617021 (-2805 2500);
PAINT SKYBLUE (-2805 2500);
FORCEPROP 1 LAST WATTAGE 1/16W
J 0
(-2810 2450);
DISPLAY 0.617021 (-2810 2450);
PAINT SKYBLUE (-2810 2450);
FORCEPROP 1 LAST MATERIAL CHIP
J 0
(-2810 2400);
DISPLAY 0.617021 (-2810 2400);
PAINT SKYBLUE (-2810 2400);
FORCEPROP 1 LAST PACK_TYPE 0402
J 0
(-2810 2300);
DISPLAY 0.617021 (-2810 2300);
PAINT SKYBLUE (-2810 2300);
FORCEPROP 1 LAST PART_NUMBER G21796-026
J 0
(-2810 2350);
DISPLAY 0.617021 (-2810 2350);
PAINT BLUE (-2810 2350);
FORCEPROP 2 LAST SEC_TYPE 0402
J 0
(-2800 2700);
DISPLAY 1.021277 (-2800 2700);
PAINT ORANGE (-2800 2700);
DISPLAY INVISIBLE (-2800 2700);
FORCEPROP 2 LAST BOM_COST SYS_CLOCK
J 0
(-2800 2650);
DISPLAY 1.361702 (-2800 2650);
PAINT ORANGE (-2800 2650);
DISPLAY INVISIBLE (-2800 2650);
FORCEPROP 2 LAST SEC 1
J 0
(-2800 2700);
DISPLAY 0.680851 (-2800 2700);
PAINT MONO (-2800 2700);
DISPLAY INVISIBLE (-2800 2700);
FORCEPROP 2 LAST CDS_LOCATION R6P20
J 0
(-2805 2600);
DISPLAY 0.617021 (-2805 2600);
PAINT AQUA (-2805 2600);
DISPLAY INVISIBLE (-2805 2600);
FORCEPROP 1 LAST PATH I81
J 0
(-2800 2650);
DISPLAY 0.978723 (-2800 2650);
PAINT WHITE (-2800 2650);
DISPLAY INVISIBLE (-2800 2650);
FORCEPROP 2 LAST ROOM DB1200ZL
J 0
(-2800 2650);
DISPLAY 1.361702 (-2800 2650);
PAINT ORANGE (-2800 2650);
DISPLAY INVISIBLE (-2800 2650);
FORCEPROP 2 LAST CDS_LIB mstr_discrete
J 0
(-2850 2475);
PAINT ORANGE (-2850 2475);
DISPLAY INVISIBLE (-2850 2475);
FORCEADD OFFPAGE..6
(1050 4500);
FORCEPROP 2 LAST $XR5 247 
J 0
(170 4500);
DISPLAY 0.638298 (170 4500);
PAINT MONO (170 4500);
FORCEPROP 2 LAST $XR4 159 
J 0
(290 4500);
DISPLAY 0.638298 (290 4500);
PAINT MONO (290 4500);
FORCEPROP 2 LAST $XR3 156 
J 0
(410 4500);
DISPLAY 0.638298 (410 4500);
PAINT MONO (410 4500);
FORCEPROP 2 LAST $XR2 138 
J 0
(530 4500);
DISPLAY 0.638298 (530 4500);
PAINT MONO (530 4500);
FORCEPROP 2 LAST $XR1 111 
J 0
(650 4500);
DISPLAY 0.638298 (650 4500);
PAINT MONO (650 4500);
FORCEPROP 2 LAST $XR0 101 
J 0
(770 4500);
DISPLAY 0.638298 (770 4500);
PAINT MONO (770 4500);
FORCEPROP 2 LAST PATH I83
J 0
(1100 4575);
DISPLAY 1.021277 (1100 4575);
PAINT ORANGE (1100 4575);
DISPLAY INVISIBLE (1100 4575);
FORCEPROP 2 LAST CDS_LIB mstr_standard
J 0
(1050 4500);
PAINT ORANGE (1050 4500);
DISPLAY INVISIBLE (1050 4500);
FORCEPROP 1 LAST OFFPAGE TRUE
J 0
(1375 4375);
DISPLAY 0.872340 (1375 4375);
PAINT GREEN (1375 4375);
DISPLAY INVISIBLE (1375 4375);
FORCEPROP 1 LAST COMMENT_BODY TRUE
J 0
(1150 4425);
DISPLAY 0.872340 (1150 4425);
PAINT GREEN (1150 4425);
DISPLAY INVISIBLE (1150 4425);
FORCEADD OFFPAGE..3
(3825 4500);
FORCEPROP 2 LAST CDS_LIB mstr_standard
J 0
(3825 4500);
PAINT ORANGE (3825 4500);
DISPLAY INVISIBLE (3825 4500);
FORCEPROP 2 LAST PATH I84
J 0
(3875 4575);
DISPLAY 1.021277 (3875 4575);
PAINT ORANGE (3875 4575);
DISPLAY INVISIBLE (3875 4575);
FORCEPROP 1 LAST OFFPAGE TRUE
J 0
(4150 4375);
DISPLAY 0.872340 (4150 4375);
PAINT GREEN (4150 4375);
DISPLAY INVISIBLE (4150 4375);
FORCEPROP 1 LAST COMMENT_BODY TRUE
J 0
(3775 4400);
DISPLAY 0.872340 (3775 4400);
PAINT GREEN (3775 4400);
DISPLAY INVISIBLE (3775 4400);
FORCEPROP 2 LAST $XR0 102 
J 0
(4039 4500);
DISPLAY 0.638298 (4039 4500);
PAINT MONO (4039 4500);
DISPLAY INVISIBLE (4039 4500);
FORCEADD OFFPAGE..1
(1050 4100);
FORCEPROP 2 LAST $XR5 247 
J 0
(198 4100);
DISPLAY 0.638298 (198 4100);
PAINT MONO (198 4100);
FORCEPROP 2 LAST $XR4 156 
J 0
(318 4100);
DISPLAY 0.638298 (318 4100);
PAINT MONO (318 4100);
FORCEPROP 2 LAST $XR3 111 
J 0
(438 4100);
DISPLAY 0.638298 (438 4100);
PAINT MONO (438 4100);
FORCEPROP 2 LAST $XR2 101 
J 0
(558 4100);
DISPLAY 0.638298 (558 4100);
PAINT MONO (558 4100);
FORCEPROP 2 LAST $XR1 159 
J 0
(678 4100);
DISPLAY 0.638298 (678 4100);
PAINT MONO (678 4100);
FORCEPROP 2 LAST $XR0 138 
J 0
(798 4100);
DISPLAY 0.638298 (798 4100);
PAINT MONO (798 4100);
FORCEPROP 2 LAST PATH I85
J 0
(1100 4175);
DISPLAY 1.021277 (1100 4175);
PAINT ORANGE (1100 4175);
DISPLAY INVISIBLE (1100 4175);
FORCEPROP 2 LAST CDS_LIB mstr_standard
J 0
(1050 4100);
PAINT ORANGE (1050 4100);
DISPLAY INVISIBLE (1050 4100);
FORCEPROP 1 LAST OFFPAGE TRUE
J 0
(1375 3975);
DISPLAY 0.872340 (1375 3975);
PAINT GREEN (1375 3975);
DISPLAY INVISIBLE (1375 3975);
FORCEPROP 1 LAST COMMENT_BODY TRUE
J 0
(1175 4000);
DISPLAY 0.872340 (1175 4000);
PAINT GREEN (1175 4000);
DISPLAY INVISIBLE (1175 4000);
FORCEADD OFFPAGE..2
(3825 4100);
FORCEPROP 2 LAST $XR0 102 
J 0
(4014 4100);
DISPLAY 0.638298 (4014 4100);
PAINT MONO (4014 4100);
FORCEPROP 2 LAST PATH I86
J 0
(4000 4175);
DISPLAY 1.021277 (4000 4175);
PAINT ORANGE (4000 4175);
DISPLAY INVISIBLE (4000 4175);
FORCEPROP 2 LAST CDS_LIB mstr_standard
J 0
(3825 4100);
PAINT ORANGE (3825 4100);
DISPLAY INVISIBLE (3825 4100);
FORCEPROP 1 LAST OFFPAGE TRUE
J 0
(4150 3975);
DISPLAY 0.872340 (4150 3975);
PAINT GREEN (4150 3975);
DISPLAY INVISIBLE (4150 3975);
FORCEPROP 1 LAST COMMENT_BODY TRUE
J 0
(3780 4005);
DISPLAY 0.872340 (3780 4005);
PAINT GREEN (3780 4005);
DISPLAY INVISIBLE (3780 4005);
FORCEADD OFFPAGE..1
(-1175 3000);
FORCEPROP 2 LAST $XR1 191 
J 0
(-1547 3000);
DISPLAY 0.638298 (-1547 3000);
PAINT MONO (-1547 3000);
FORCEPROP 2 LAST $XR0 102 
J 0
(-1427 3000);
DISPLAY 0.638298 (-1427 3000);
PAINT MONO (-1427 3000);
FORCEPROP 2 LAST PATH I89
J 0
(-1125 3075);
DISPLAY 1.021277 (-1125 3075);
PAINT ORANGE (-1125 3075);
DISPLAY INVISIBLE (-1125 3075);
FORCEPROP 2 LAST CDS_LIB mstr_standard
J 0
(-1175 3000);
PAINT ORANGE (-1175 3000);
DISPLAY INVISIBLE (-1175 3000);
FORCEPROP 1 LAST OFFPAGE TRUE
J 0
(-850 2875);
PAINT GREEN (-850 2875);
DISPLAY INVISIBLE (-850 2875);
FORCEPROP 1 LAST COMMENT_BODY TRUE
J 0
(-1050 2900);
DISPLAY 1.404255 (-1050 2900);
PAINT PEACH (-1050 2900);
DISPLAY INVISIBLE (-1050 2900);
FORCEADD P3V3..1
(1475 1275);
FORCEPROP 3 LASTPIN (1475 1225) SIG_NAME P3V3\g
J 0
(1485 1235);
DISPLAY 0.659574 (1485 1235);
PAINT MONO (1485 1235);
DISPLAY INVISIBLE (1485 1235);
FORCEPROP 2 LAST CDS_LIB mstr_symbols
J 0
(1475 1275);
PAINT ORANGE (1475 1275);
DISPLAY INVISIBLE (1475 1275);
FORCEPROP 1 LAST SIZE 1B
J 0
(1520 1297);
DISPLAY 0.340426 (1520 1297);
PAINT GREEN (1520 1297);
DISPLAY INVISIBLE (1520 1297);
FORCEPROP 1 LAST VOLTAGE 3.3V
J 0
(1430 1232);
DISPLAY 0.340426 (1430 1232);
PAINT SKYBLUE (1430 1232);
DISPLAY INVISIBLE (1430 1232);
FORCEPROP 1 LAST PATH I9
J 0
(1520 1277);
DISPLAY 0.340426 (1520 1277);
PAINT GREEN (1520 1277);
DISPLAY INVISIBLE (1520 1277);
FORCEPROP 1 LAST BODY_TYPE PLUMBING
J 0
(1430 1232);
DISPLAY 0.340426 (1430 1232);
PAINT GREEN (1430 1232);
DISPLAY INVISIBLE (1430 1232);
FORCEPROP 1 LAST HDL_POWER P3V3
J 0
(1150 1150);
DISPLAY 0.872340 (1150 1150);
PAINT ORANGE (1150 1150);
DISPLAY INVISIBLE (1150 1150);
FORCEADD OFFPAGE..1
(-1175 2700);
FORCEPROP 2 LAST $XR1 191 
J 0
(-1547 2700);
DISPLAY 0.638298 (-1547 2700);
PAINT MONO (-1547 2700);
FORCEPROP 2 LAST $XR0 102 
J 0
(-1427 2700);
DISPLAY 0.638298 (-1427 2700);
PAINT MONO (-1427 2700);
FORCEPROP 2 LAST PATH I90
J 0
(-1125 2775);
DISPLAY 1.021277 (-1125 2775);
PAINT ORANGE (-1125 2775);
DISPLAY INVISIBLE (-1125 2775);
FORCEPROP 2 LAST CDS_LIB mstr_standard
J 0
(-1175 2700);
PAINT ORANGE (-1175 2700);
DISPLAY INVISIBLE (-1175 2700);
FORCEPROP 1 LAST OFFPAGE TRUE
J 0
(-850 2575);
PAINT GREEN (-850 2575);
DISPLAY INVISIBLE (-850 2575);
FORCEPROP 1 LAST COMMENT_BODY TRUE
J 0
(-1050 2600);
DISPLAY 1.404255 (-1050 2600);
PAINT PEACH (-1050 2600);
DISPLAY INVISIBLE (-1050 2600);
FORCEADD RES..2
R 2
(-125 1075);
FORCEPROP 1 LAST TOLERANCE 1%
J 2
(-170 1100);
DISPLAY 0.617021 (-170 1100);
PAINT SKYBLUE (-170 1100);
FORCEPROP 1 LASTPIN (-125 1175) $PN 1
J 2
(-130 1137);
DISPLAY 0.617021 (-130 1137);
PAINT ORANGE (-130 1137);
FORCEPROP 1 LASTPIN (-125 975) $PN 2
J 2
(-130 985);
DISPLAY 0.617021 (-130 985);
PAINT ORANGE (-130 985);
FORCEPROP 1 LAST PACK_TYPE 0402
J 2
(-165 900);
DISPLAY 0.617021 (-165 900);
PAINT SKYBLUE (-165 900);
FORCEPROP 1 LAST MATERIAL CHIP
J 2
(-165 1000);
DISPLAY 0.617021 (-165 1000);
PAINT SKYBLUE (-165 1000);
FORCEPROP 1 LAST PART_NUMBER G21796-072
J 2
(-165 950);
DISPLAY 0.617021 (-165 950);
PAINT BLUE (-165 950);
FORCEPROP 1 LAST WATTAGE 1/16W
J 2
(-165 1050);
DISPLAY 0.617021 (-165 1050);
PAINT SKYBLUE (-165 1050);
FORCEPROP 1 LAST VALUE 4.75K
J 2
(-170 1150);
DISPLAY 0.617021 (-170 1150);
PAINT SKYBLUE (-170 1150);
FORCEPROP 1 LAST LOCATION R4D69
J 2
(-170 1200);
DISPLAY 0.617021 (-170 1200);
PAINT AQUA (-170 1200);
FORCEPROP 2 LAST BOM_COST SYS_CLOCK
J 0
(-150 1225);
PAINT MONO (-150 1225);
DISPLAY INVISIBLE (-150 1225);
FORCEPROP 2 LAST SIGNAL_MODEL DEFAULT_RESISTOR_47000OHM_2_1
J 0
(-175 1300);
PAINT MONO (-175 1300);
DISPLAY INVISIBLE (-175 1300);
FORCEPROP 2 LAST SEC_TYPE 0402
J 0
(-175 1300);
DISPLAY 1.021277 (-175 1300);
PAINT ORANGE (-175 1300);
DISPLAY INVISIBLE (-175 1300);
FORCEPROP 1 LAST PATH I93
J 2
(-175 1250);
DISPLAY 0.978723 (-175 1250);
PAINT WHITE (-175 1250);
DISPLAY INVISIBLE (-175 1250);
FORCEPROP 2 LAST SEC 1
J 0
(-175 1300);
DISPLAY 0.680851 (-175 1300);
PAINT MONO (-175 1300);
DISPLAY INVISIBLE (-175 1300);
FORCEPROP 2 LAST ROOM DB1200ZL
J 0
(-150 1175);
PAINT MONO (-150 1175);
DISPLAY INVISIBLE (-150 1175);
FORCEPROP 2 LAST CDS_LIB mstr_discrete
J 0
(-125 1075);
PAINT ORANGE (-125 1075);
DISPLAY INVISIBLE (-125 1075);
FORCEADD RES..2
R 2
(200 1075);
FORCEPROP 1 LAST VALUE 4.75K
J 2
(155 1150);
DISPLAY 0.617021 (155 1150);
PAINT SKYBLUE (155 1150);
FORCEPROP 1 LAST LOCATION R4D70
J 2
(155 1200);
DISPLAY 0.617021 (155 1200);
PAINT AQUA (155 1200);
FORCEPROP 1 LASTPIN (200 975) $PN 2
J 2
(195 985);
DISPLAY 0.617021 (195 985);
PAINT ORANGE (195 985);
FORCEPROP 1 LAST TOLERANCE 1%
J 2
(155 1100);
DISPLAY 0.617021 (155 1100);
PAINT SKYBLUE (155 1100);
FORCEPROP 1 LASTPIN (200 1175) $PN 1
J 2
(195 1137);
DISPLAY 0.617021 (195 1137);
PAINT ORANGE (195 1137);
FORCEPROP 1 LAST PART_NUMBER G21796-072
J 2
(160 950);
DISPLAY 0.617021 (160 950);
PAINT BLUE (160 950);
FORCEPROP 1 LAST MATERIAL CHIP
J 2
(160 1000);
DISPLAY 0.617021 (160 1000);
PAINT SKYBLUE (160 1000);
FORCEPROP 1 LAST WATTAGE 1/16W
J 2
(160 1050);
DISPLAY 0.617021 (160 1050);
PAINT SKYBLUE (160 1050);
FORCEPROP 1 LAST PACK_TYPE 0402
J 2
(160 900);
DISPLAY 0.617021 (160 900);
PAINT SKYBLUE (160 900);
FORCEPROP 2 LAST SIGNAL_MODEL DEFAULT_RESISTOR_47000OHM_2_1
J 0
(150 1300);
PAINT MONO (150 1300);
DISPLAY INVISIBLE (150 1300);
FORCEPROP 2 LAST BOM_COST SYS_CLOCK
J 0
(175 1225);
PAINT MONO (175 1225);
DISPLAY INVISIBLE (175 1225);
FORCEPROP 2 LAST SEC_TYPE 0402
J 0
(150 1300);
DISPLAY 1.021277 (150 1300);
PAINT ORANGE (150 1300);
DISPLAY INVISIBLE (150 1300);
FORCEPROP 1 LAST PATH I94
J 2
(150 1250);
DISPLAY 0.978723 (150 1250);
PAINT WHITE (150 1250);
DISPLAY INVISIBLE (150 1250);
FORCEPROP 2 LAST SEC 1
J 0
(150 1300);
DISPLAY 0.680851 (150 1300);
PAINT MONO (150 1300);
DISPLAY INVISIBLE (150 1300);
FORCEPROP 2 LAST ROOM DB1200ZL
J 0
(175 1175);
PAINT MONO (175 1175);
DISPLAY INVISIBLE (175 1175);
FORCEPROP 2 LAST CDS_LIB mstr_discrete
J 0
(200 1075);
PAINT ORANGE (200 1075);
DISPLAY INVISIBLE (200 1075);
FORCEADD P3V3..1
(-750 1375);
FORCEPROP 3 LASTPIN (-750 1325) SIG_NAME P3V3\g
J 0
(-740 1335);
DISPLAY 0.659574 (-740 1335);
PAINT MONO (-740 1335);
DISPLAY INVISIBLE (-740 1335);
FORCEPROP 1 LAST HDL_POWER P3V3
J 0
(-1075 1250);
DISPLAY 0.872340 (-1075 1250);
PAINT ORANGE (-1075 1250);
DISPLAY INVISIBLE (-1075 1250);
FORCEPROP 1 LAST BODY_TYPE PLUMBING
J 0
(-795 1332);
DISPLAY 0.340426 (-795 1332);
PAINT GREEN (-795 1332);
DISPLAY INVISIBLE (-795 1332);
FORCEPROP 1 LAST VOLTAGE 3.3V
J 0
(-795 1332);
DISPLAY 0.340426 (-795 1332);
PAINT SKYBLUE (-795 1332);
DISPLAY INVISIBLE (-795 1332);
FORCEPROP 2 LAST CDS_LIB mstr_symbols
J 0
(-750 1375);
PAINT ORANGE (-750 1375);
DISPLAY INVISIBLE (-750 1375);
FORCEPROP 1 LAST SIZE 1B
J 0
(-705 1397);
DISPLAY 0.340426 (-705 1397);
PAINT GREEN (-705 1397);
DISPLAY INVISIBLE (-705 1397);
FORCEPROP 1 LAST PATH I95
J 0
(-705 1377);
DISPLAY 0.340426 (-705 1377);
PAINT GREEN (-705 1377);
DISPLAY INVISIBLE (-705 1377);
FORCEADD OFFPAGE..2
(775 875);
FORCEPROP 2 LAST $XR1 102 
J 0
(1084 875);
DISPLAY 0.638298 (1084 875);
PAINT MONO (1084 875);
FORCEPROP 2 LAST $XR0 191 
J 0
(964 875);
DISPLAY 0.638298 (964 875);
PAINT MONO (964 875);
FORCEPROP 2 LAST PATH I96
J 0
(950 950);
DISPLAY 1.021277 (950 950);
PAINT ORANGE (950 950);
DISPLAY INVISIBLE (950 950);
FORCEPROP 2 LAST CDS_LIB mstr_standard
J 0
(775 875);
PAINT ORANGE (775 875);
DISPLAY INVISIBLE (775 875);
FORCEPROP 1 LAST OFFPAGE TRUE
J 0
(1100 750);
DISPLAY 0.872340 (1100 750);
PAINT GREEN (1100 750);
DISPLAY INVISIBLE (1100 750);
FORCEPROP 1 LAST COMMENT_BODY TRUE
J 0
(730 780);
DISPLAY 0.872340 (730 780);
PAINT GREEN (730 780);
DISPLAY INVISIBLE (730 780);
FORCEADD OFFPAGE..2
(775 825);
FORCEPROP 2 LAST $XR1 102 
J 0
(1084 825);
DISPLAY 0.638298 (1084 825);
PAINT MONO (1084 825);
FORCEPROP 2 LAST $XR0 191 
J 0
(964 825);
DISPLAY 0.638298 (964 825);
PAINT MONO (964 825);
FORCEPROP 2 LAST PATH I97
J 0
(950 900);
DISPLAY 1.021277 (950 900);
PAINT ORANGE (950 900);
DISPLAY INVISIBLE (950 900);
FORCEPROP 2 LAST CDS_LIB mstr_standard
J 0
(775 825);
PAINT ORANGE (775 825);
DISPLAY INVISIBLE (775 825);
FORCEPROP 1 LAST OFFPAGE TRUE
J 0
(1100 700);
DISPLAY 0.872340 (1100 700);
PAINT GREEN (1100 700);
DISPLAY INVISIBLE (1100 700);
FORCEPROP 1 LAST COMMENT_BODY TRUE
J 0
(730 730);
DISPLAY 0.872340 (730 730);
PAINT GREEN (730 730);
DISPLAY INVISIBLE (730 730);
FORCEADD OFFPAGE..2
(775 775);
FORCEPROP 2 LAST $XR1 102 
J 0
(1084 775);
DISPLAY 0.638298 (1084 775);
PAINT MONO (1084 775);
FORCEPROP 2 LAST $XR0 190 
J 0
(964 775);
DISPLAY 0.638298 (964 775);
PAINT MONO (964 775);
FORCEPROP 2 LAST PATH I98
J 0
(950 850);
DISPLAY 1.021277 (950 850);
PAINT ORANGE (950 850);
DISPLAY INVISIBLE (950 850);
FORCEPROP 2 LAST CDS_LIB mstr_standard
J 0
(775 775);
PAINT ORANGE (775 775);
DISPLAY INVISIBLE (775 775);
FORCEPROP 1 LAST OFFPAGE TRUE
J 0
(1100 650);
DISPLAY 0.872340 (1100 650);
PAINT GREEN (1100 650);
DISPLAY INVISIBLE (1100 650);
FORCEPROP 1 LAST COMMENT_BODY TRUE
J 0
(730 680);
DISPLAY 0.872340 (730 680);
PAINT GREEN (730 680);
DISPLAY INVISIBLE (730 680);
FORCEADD OFFPAGE..1
(-1175 2850);
FORCEPROP 2 LAST $XR1 190 
J 0
(-1547 2850);
DISPLAY 0.638298 (-1547 2850);
PAINT MONO (-1547 2850);
FORCEPROP 2 LAST $XR0 102 
J 0
(-1427 2850);
DISPLAY 0.638298 (-1427 2850);
PAINT MONO (-1427 2850);
FORCEPROP 2 LAST CDS_LIB mstr_standard
J 0
(-1175 2850);
PAINT MONO (-1175 2850);
DISPLAY INVISIBLE (-1175 2850);
FORCEPROP 2 LAST PATH I99
J 0
(-1425 2900);
DISPLAY 1.021277 (-1425 2900);
PAINT ORANGE (-1425 2900);
DISPLAY INVISIBLE (-1425 2900);
FORCEPROP 1 LAST OFFPAGE TRUE
J 0
(-850 2725);
PAINT GREEN (-850 2725);
DISPLAY INVISIBLE (-850 2725);
FORCEPROP 1 LAST COMMENT_BODY TRUE
J 0
(-1050 2750);
DISPLAY 1.404255 (-1050 2750);
PAINT PEACH (-1050 2750);
DISPLAY INVISIBLE (-1050 2750);
FORCEADD DNS..2
(-2920 1020);
PAINT RED (-2920 1020);
FORCEPROP 2 LAST CDS_LIB mstr_misc
J 0
(-2920 1020);
PAINT ORANGE (-2920 1020);
DISPLAY INVISIBLE (-2920 1020);
FORCEPROP 1 LAST COMMENT_BODY TRUE
R 1
J 0
(-2845 795);
DISPLAY 0.872340 (-2845 795);
PAINT GREEN (-2845 795);
DISPLAY INVISIBLE (-2845 795);
FORCEADD DNS..2
(-1645 1995);
PAINT RED (-1645 1995);
FORCEPROP 2 LAST CDS_LIB mstr_misc
J 0
(-1645 1995);
PAINT ORANGE (-1645 1995);
DISPLAY INVISIBLE (-1645 1995);
FORCEPROP 1 LAST COMMENT_BODY TRUE
R 1
J 0
(-1570 1770);
DISPLAY 0.872340 (-1570 1770);
PAINT GREEN (-1570 1770);
DISPLAY INVISIBLE (-1570 1770);
FORCEADD DESIGN_NOTE..1
(-2125 1550);
PAINT PURPLE (-2125 1550);
FORCEPROP 0 LAST L1 '0' FOR 133M MODE
J 0
(-2325 1425);
DISPLAY 0.808511 (-2325 1425);
PAINT VIOLET (-2325 1425);
FORCEPROP 0 LAST L2 '1' FOR 100M MODE
J 0
(-2325 1375);
DISPLAY 0.808511 (-2325 1375);
PAINT VIOLET (-2325 1375);
FORCEPROP 2 LAST CDS_LIB mstr_symbols
J 0
(-2125 1550);
PAINT ORANGE (-2125 1550);
DISPLAY INVISIBLE (-2125 1550);
FORCEPROP 2 LAST BOM_COST SYS_CLOCK
J 0
(-2325 1500);
PAINT MONO (-2325 1500);
DISPLAY INVISIBLE (-2325 1500);
FORCEPROP 2 LAST ROOM DB1200ZL
J 0
(-2325 1500);
PAINT MONO (-2325 1500);
DISPLAY INVISIBLE (-2325 1500);
FORCEPROP 1 LAST COMMENT_BODY TRUE
J 0
(-2100 1650);
DISPLAY 1.319149 (-2100 1650);
PAINT GREEN (-2100 1650);
DISPLAY INVISIBLE (-2100 1650);
FORCEADD DNS..2
(-2670 1020);
PAINT RED (-2670 1020);
FORCEPROP 2 LAST CDS_LIB mstr_misc
J 0
(-2670 1020);
PAINT ORANGE (-2670 1020);
DISPLAY INVISIBLE (-2670 1020);
FORCEPROP 1 LAST COMMENT_BODY TRUE
R 1
J 0
(-2595 795);
DISPLAY 0.872340 (-2595 795);
PAINT GREEN (-2595 795);
DISPLAY INVISIBLE (-2595 795);
FORCEADD DESIGN_NOTE..1
(-2125 1000);
PAINT PURPLE (-2125 1000);
FORCEPROP 0 LAST L3 PU & PD FOR BYPASS MODE
J 0
(-2325 775);
DISPLAY 0.808511 (-2325 775);
PAINT ORANGE (-2325 775);
FORCEPROP 0 LAST L2 '1' FOR HBW MODE (DEFAULT)
J 0
(-2325 825);
DISPLAY 0.808511 (-2325 825);
PAINT VIOLET (-2325 825);
FORCEPROP 0 LAST L1 '0' FOR LBW MODE
J 0
(-2325 875);
DISPLAY 0.808511 (-2325 875);
PAINT VIOLET (-2325 875);
FORCEPROP 2 LAST ROOM DB1200ZL
J 0
(-2325 950);
PAINT MONO (-2325 950);
DISPLAY INVISIBLE (-2325 950);
FORCEPROP 2 LAST CDS_LIB mstr_symbols
J 0
(-2125 1000);
PAINT ORANGE (-2125 1000);
DISPLAY INVISIBLE (-2125 1000);
FORCEPROP 2 LAST BOM_COST SYS_CLOCK
J 0
(-2325 950);
PAINT MONO (-2325 950);
DISPLAY INVISIBLE (-2325 950);
FORCEPROP 1 LAST COMMENT_BODY TRUE
J 0
(-2100 1100);
DISPLAY 1.319149 (-2100 1100);
PAINT GREEN (-2100 1100);
DISPLAY INVISIBLE (-2100 1100);
FORCEADD DNS..2
(-3220 2845);
PAINT RED (-3220 2845);
FORCEPROP 2 LAST CDS_LIB mstr_misc
J 0
(-3220 2845);
PAINT ORANGE (-3220 2845);
DISPLAY INVISIBLE (-3220 2845);
FORCEPROP 1 LAST COMMENT_BODY TRUE
R 1
J 0
(-3145 2620);
DISPLAY 0.872340 (-3145 2620);
PAINT GREEN (-3145 2620);
DISPLAY INVISIBLE (-3145 2620);
FORCEADD DNS..2
(-2845 2845);
PAINT RED (-2845 2845);
FORCEPROP 2 LAST CDS_LIB mstr_misc
J 0
(-2845 2845);
PAINT ORANGE (-2845 2845);
DISPLAY INVISIBLE (-2845 2845);
FORCEPROP 1 LAST COMMENT_BODY TRUE
R 1
J 0
(-2770 2620);
DISPLAY 0.872340 (-2770 2620);
PAINT GREEN (-2770 2620);
DISPLAY INVISIBLE (-2770 2620);
FORCEADD DESIGN_NOTE..1
(2850 3025);
FORCEPROP 0 LAST L1 RC CLKS USED FOR DEBUG ONLY
J 0
(2675 2900);
DISPLAY 1.021277 (2675 2900);
PAINT ORANGE (2675 2900);
FORCEPROP 2 LAST CDS_LIB mstr_symbols
J 0
(2850 3025);
PAINT ORANGE (2850 3025);
DISPLAY INVISIBLE (2850 3025);
FORCEPROP 1 LAST COMMENT_BODY TRUE
J 0
(2875 3125);
DISPLAY 0.978723 (2875 3125);
PAINT ORANGE (2875 3125);
DISPLAY INVISIBLE (2875 3125);
FORCEADD INTEL_CORP_BPAGE..1
(4250 200);
FORCEPROP 1 LAST CDS_CON_LAST_MODIFIED Fri Jun 16 17:48:41 2017
J 0
(2825 525);
PAINT ORANGE (2825 525);
DISPLAY INVISIBLE (2825 525);
FORCEPROP 1 LAST CUSTOM_TXT_CDS <CURRENT_DESIGN_SHEET> OF <TOTAL_DESIGN_SHEETS>
J 0
(3750 225);
PAINT ORANGE (3750 225);
FORCEPROP 1 LAST CUSTOM_TXT_CDS <CON_LAST_MODIFIED>
J 0
(250 300);
PAINT ORANGE (250 300);
FORCEPROP 2 LAST CUSTOM_TXT_CDS <XR_PAGE_TITLE>
J 0
(-3640 5450);
DISPLAY 0.638298 (-3640 5450);
PAINT PINK (-3640 5450);
DISPLAY INVISIBLE (-3640 5450);
FORCEPROP 1 LAST SCH_TITLE DB1200ZL
J 0
(-3700 250);
DISPLAY 1.212766 (-3700 250);
PAINT ORANGE (-3700 250);
FORCEPROP 2 LAST PAGE_BORDER TRUE
J 0
(-3640 5450);
DISPLAY 0.638298 (-3640 5450);
PAINT PINK (-3640 5450);
DISPLAY INVISIBLE (-3640 5450);
FORCEPROP 2 LAST CDS_LIB mstr_symbols
J 0
(4250 200);
PAINT MONO (4250 200);
DISPLAY INVISIBLE (4250 200);
FORCEPROP 1 LAST COMMENT_BODY TRUE
J 0
(4262 212);
DISPLAY 0.468085 (4262 212);
PAINT GREEN (4262 212);
DISPLAY INVISIBLE (4262 212);
FORCEPROP 2 LAST CDS_XR_PAGE_TITLE CR-102 : @BASEBOARD_FAB2_LIB.BASEBOARD_FAB2(SCH_1):PAGE102
J 0
(-3640 5450);
DISPLAY 0.638298 (-3640 5450);
PAINT PINK (-3640 5450);
DISPLAY INVISIBLE (-3640 5450);
WIRE 16 -1 (2450 5050)(2450 5000);
WIRE 16 -1 (3650 5050)(3650 4950);
WIRE 16 -1 (3300 4950)(3650 4950);
WIRE 16 -1 (3650 4950)(3650 4850);
WIRE 16 -1 (3300 4850)(3300 4950);
WIRE 16 -1 (-2400 2500)(-2400 2450);
WIRE 16 -1 (-950 1750)(-950 1700);
WIRE 16 -1 (3700 675)(3700 600);
WIRE 16 -1 (3700 675)(3475 675);
WIRE 16 -1 (3700 800)(3700 675);
WIRE 16 -1 (3475 675)(3275 675);
WIRE 16 -1 (3475 800)(3475 675);
WIRE 16 -1 (3275 675)(3050 675);
WIRE 16 -1 (3275 800)(3275 675);
WIRE 16 -1 (3050 675)(2825 675);
WIRE 16 -1 (3050 800)(3050 675);
WIRE 16 -1 (2825 675)(2575 675);
WIRE 16 -1 (2825 800)(2825 675);
WIRE 16 -1 (2575 675)(2275 675);
WIRE 16 -1 (2575 800)(2575 675);
WIRE 16 -1 (2275 675)(1975 675);
WIRE 16 -1 (2275 800)(2275 675);
WIRE 16 -1 (1975 675)(1975 800);
WIRE 16 -1 (-1550 3700)(-1550 3600);
WIRE 16 -1 (-1800 3700)(-1550 3700);
WIRE 16 -1 (-1550 3700)(-1550 3800);
WIRE 16 -1 (-1800 3800)(-1800 3700);
WIRE 16 -1 (3700 1125)(3700 1250);
WIRE 16 -1 (3700 1125)(3475 1125);
WIRE 16 -1 (3700 1000)(3700 1125);
WIRE 16 -1 (3275 1125)(3475 1125);
WIRE 16 -1 (3475 1000)(3475 1125);
WIRE 16 -1 (3275 1125)(3050 1125);
WIRE 16 -1 (3275 1000)(3275 1125);
WIRE 16 -1 (3050 1125)(2825 1125);
WIRE 16 -1 (3050 1000)(3050 1125);
WIRE 16 -1 (2825 1125)(2575 1125);
WIRE 16 -1 (2825 1000)(2825 1125);
WIRE 16 -1 (2575 1125)(2275 1125);
WIRE 16 -1 (2575 1000)(2575 1125);
WIRE 16 -1 (2275 1125)(1975 1125);
WIRE 16 -1 (2275 1000)(2275 1125);
WIRE 16 -1 (1975 1000)(1975 1125);
WIRE 16 -1 (1800 1125)(1975 1125);
WIRE 16 -1 (-2800 4125)(-2800 4200);
WIRE 16 -1 (-2525 4125)(-2800 4125);
WIRE 16 -1 (-825 3750)(-825 3875);
WIRE 16 -1 (-825 3750)(-825 3700);
WIRE 16 -1 (-300 3750)(-825 3750);
WIRE 16 -1 (-825 3700)(-825 3650);
WIRE 16 -1 (-300 3700)(-825 3700);
WIRE 16 -1 (-825 3650)(-825 3600);
WIRE 16 -1 (-300 3650)(-825 3650);
WIRE 16 -1 (-825 3600)(-825 3550);
WIRE 16 -1 (-300 3600)(-825 3600);
WIRE 16 -1 (-825 3550)(-825 3500);
WIRE 16 -1 (-300 3550)(-825 3550);
WIRE 16 -1 (-825 3500)(-825 3450);
WIRE 16 -1 (-300 3500)(-825 3500);
WIRE 16 -1 (-300 3450)(-825 3450);
WIRE 16 -1 (-3125 3400)(-3125 3500);
WIRE 16 -1 (-2925 3400)(-3125 3400);
WIRE 16 -1 (-2325 3000)(-2325 2950);
WIRE 16 -1 (-2575 3000)(-2325 3000);
WIRE 16 -1 (-2325 3000)(-2325 3125);
WIRE 16 -1 (-2575 3125)(-2575 3000);
WIRE 16 -1 (-3225 3100)(-3225 3050);
WIRE 16 -1 (-3225 3050)(-2850 3050);
WIRE 16 -1 (-3225 2950)(-3225 3050);
WIRE 16 -1 (-2850 3050)(-2850 2950);
WIRE 16 -1 (-2850 2225)(-2850 2175);
WIRE 16 -1 (-3225 2225)(-2850 2225);
WIRE 16 -1 (-2850 2225)(-2850 2375);
WIRE 16 -1 (-3225 2375)(-3225 2225);
WIRE 16 -1 (-2925 1650)(-2925 1750);
WIRE 16 -1 (-2675 1650)(-2925 1650);
WIRE 16 -1 (-2925 1650)(-2925 1525);
WIRE 16 -1 (-2675 1525)(-2675 1650);
WIRE 16 -1 (-2675 750)(-2675 850);
WIRE 16 -1 (-2925 850)(-2675 850);
WIRE 16 -1 (-2675 925)(-2675 850);
WIRE 16 -1 (-2925 850)(-2925 925);
WIRE 16 -1 (1425 1950)(1425 1775);
WIRE 16 -1 (1425 2000)(1425 1950);
WIRE 16 -1 (1425 1950)(1000 1950);
WIRE 16 -1 (1425 2050)(1425 2000);
WIRE 16 -1 (1000 2000)(1425 2000);
WIRE 16 -1 (1425 2100)(1425 2050);
WIRE 16 -1 (1000 2050)(1425 2050);
WIRE 16 -1 (1425 2150)(1425 2100);
WIRE 16 -1 (1000 2100)(1425 2100);
WIRE 16 -1 (1425 2200)(1425 2150);
WIRE 16 -1 (1000 2150)(1425 2150);
WIRE 16 -1 (1425 2250)(1425 2200);
WIRE 16 -1 (1000 2200)(1425 2200);
WIRE 16 -1 (1425 2300)(1425 2250);
WIRE 16 -1 (1000 2250)(1425 2250);
WIRE 16 -1 (1000 2300)(1425 2300);
WIRE 16 -1 (1475 1225)(1475 1125);
WIRE 16 -1 (1475 1125)(1600 1125);
WIRE 16 -1 (-750 1300)(-750 1325);
WIRE 16 -1 (-125 1300)(-750 1300);
WIRE 16 -1 (-750 1175)(-750 1300);
WIRE 16 -1 (-125 1300)(200 1300);
WIRE 16 -1 (-125 1175)(-125 1300);
WIRE 16 -1 (200 1175)(200 1300);
WIRE 16 -1 (-300 3800)(-550 3800);
WIRE 16 -1 (-1800 4000)(-1800 4125);
WIRE 16 -1 (-1800 4125)(-2325 4125);
WIRE 16 -1 (-1550 4000)(-1550 4125);
WIRE 16 -1 (-1550 4125)(-1800 4125);
WIRE 16 -1 (-550 3800)(-550 4125);
WIRE 16 -1 (-550 4125)(-1550 4125);
FORCEPROP 0 LAST VOLTAGE +3.3V
J 0
(-900 4175);
DISPLAY 1.021277 (-900 4175);
PAINT SKYBLUE (-900 4175);
DISPLAY INVISIBLE (-900 4175);
FORCEPROP 0 LAST SIG_NAME P3V3_DB1200_A
J 0
(-1760 4135);
DISPLAY 0.617021 (-1760 4135);
PAINT ORANGE (-1760 4135);
FORCEPROP 2 LASTPROP $XRERR UNIQUE?
J 0
(-2000 4135);
DISPLAY 0.638298 (-2000 4135);
PAINT MONO (-2000 4135);
DISPLAY INVISIBLE (-2000 4135);
WIRE 3 682 (-800 1250)(-800 850);
WIRE 3 682 (-450 1250)(-800 1250);
WIRE 3 682 (-800 850)(-450 850);
WIRE 3 682 (-450 850)(-450 1250);
WIRE 16 -1 (-750 775)(725 775);
FORCEPROP 2 LAST SIG_NAME FM_DB1200ZL_BCLKS_EN_N
J 0
(240 785);
DISPLAY 0.617021 (240 785);
PAINT ORANGE (240 785);
WIRE 16 -1 (-750 975)(-750 775);
WIRE 16 -1 (-125 825)(725 825);
FORCEPROP 2 LAST SIG_NAME FM_CPU1_MCP_CLK_EN_N
J 0
(240 835);
DISPLAY 0.617021 (240 835);
PAINT ORANGE (240 835);
WIRE 16 -1 (-125 975)(-125 825);
WIRE 16 -1 (-300 1500)(-1150 1500);
FORCEPROP 0 LAST SIG_NAME FM_100M_N
J 0
(-1110 1510);
DISPLAY 0.617021 (-1110 1510);
PAINT ORANGE (-1110 1510);
WIRE 16 -1 (-300 1500)(-300 2000);
WIRE 16 -1 (-300 2100)(-350 2100);
WIRE 16 -1 (-350 1550)(-1150 1550);
FORCEPROP 0 LAST SIG_NAME FM_HBW_BYPASS_LOWBW_N
J 0
(-1110 1560);
DISPLAY 0.617021 (-1110 1560);
PAINT ORANGE (-1110 1560);
WIRE 16 -1 (-350 1550)(-350 2100);
WIRE 16 -1 (1000 2450)(1975 2450);
FORCEPROP 2 LAST SIG_NAME CLK_100M_CPU0_BCLK0_R_DN
J 0
(1125 2460);
DISPLAY 0.617021 (1125 2460);
PAINT ORANGE (1125 2460);
WIRE 16 -1 (1000 2500)(1975 2500);
FORCEPROP 2 LAST SIG_NAME CLK_100M_CPU0_BCLK0_R_DP
J 0
(1125 2510);
DISPLAY 0.617021 (1125 2510);
PAINT ORANGE (1125 2510);
WIRE 16 -1 (1000 3550)(1975 3550);
FORCEPROP 2 LAST SIG_NAME CLK_100M_CPU1_RC_REFCLK1_R_DN
J 0
(1125 3560);
DISPLAY 0.617021 (1125 3560);
PAINT ORANGE (1125 3560);
WIRE 16 -1 (-300 2900)(-525 2900);
WIRE 16 -1 (-525 3000)(-1125 3000);
FORCEPROP 2 LAST SIG_NAME FM_CPU1_MCP_CLK_EN_N
J 0
(-1125 3010);
DISPLAY 0.617021 (-1125 3010);
PAINT ORANGE (-1125 3010);
WIRE 16 -1 (-525 3000)(-300 3000);
WIRE 16 -1 (-525 2950)(-525 3000);
WIRE 16 -1 (-525 2950)(-525 2900);
WIRE 16 -1 (-300 2950)(-525 2950);
WIRE 16 -1 (-2400 2250)(-2400 2200);
WIRE 16 -1 (-950 2200)(-950 2150);
WIRE 16 -1 (-950 2200)(-300 2200);
WIRE 16 -1 (-2400 2200)(-1650 2200);
WIRE 16 -1 (-1650 2200)(-1650 2100);
WIRE 16 -1 (-1650 2200)(-950 2200);
FORCEPROP 2 LAST SIG_NAME FM_DB1200_PWRGD_R
J 0
(-1485 2210);
DISPLAY 0.638298 (-1485 2210);
PAINT ORANGE (-1485 2210);
FORCEPROP 2 LASTPROP $XRERR UNIQUE?
J 0
(-1725 2210);
DISPLAY 0.638298 (-1725 2210);
PAINT MONO (-1725 2210);
DISPLAY INVISIBLE (-1725 2210);
WIRE 16 -1 (-300 2350)(-1675 2350);
FORCEPROP 0 LAST SIG_NAME CLK_100M_DB1200_DP
J 0
(-1635 2360);
DISPLAY 0.617021 (-1635 2360);
PAINT ORANGE (-1635 2360);
WIRE 16 -1 (-1675 2300)(-300 2300);
FORCEPROP 0 LAST SIG_NAME CLK_100M_DB1200_DN
J 0
(-1635 2310);
DISPLAY 0.617021 (-1635 2310);
PAINT ORANGE (-1635 2310);
WIRE 3 682 (-1200 1725)(-550 1725);
WIRE 3 682 (-1200 2125)(-1200 1725);
WIRE 3 682 (-550 1725)(-550 2125);
WIRE 3 682 (-550 2125)(-1200 2125);
WIRE 16 -1 (-1650 1850)(-2300 1850);
FORCEPROP 0 LAST SIG_NAME FM_DB1200_PWRGD
J 0
(-2260 1860);
DISPLAY 0.617021 (-2260 1860);
PAINT ORANGE (-2260 1860);
WIRE 16 -1 (-1650 1850)(-1650 1900);
WIRE 16 -1 (-1150 1850)(-1650 1850);
WIRE 3 682 (1750 3925)(1750 5025);
WIRE 3 682 (4125 3925)(1750 3925);
WIRE 3 682 (1750 5025)(4125 5025);
WIRE 3 682 (4125 5025)(4125 3925);
WIRE 3 682 (-2500 2475)(-2500 2150);
WIRE 3 682 (-2000 2475)(-2500 2475);
WIRE 3 682 (-2500 2150)(-2000 2150);
WIRE 3 682 (-2000 2150)(-2000 2475);
WIRE 16 -1 (-1125 3100)(-300 3100);
FORCEPROP 2 LAST SIG_NAME SMB_HOST_STBY_LVC3_SCL_R2
J 0
(-1125 3110);
DISPLAY 0.617021 (-1125 3110);
PAINT ORANGE (-1125 3110);
WIRE 16 -1 (-300 2450)(-425 2450);
WIRE 16 -1 (-425 2450)(-425 2500);
WIRE 16 -1 (-300 2500)(-425 2500);
WIRE 16 -1 (-425 2500)(-425 2550);
WIRE 16 -1 (-300 2550)(-425 2550);
WIRE 16 -1 (-425 2750)(-425 2550);
WIRE 16 -1 (-300 2750)(-425 2750);
WIRE 16 -1 (-425 2750)(-425 2800);
WIRE 16 -1 (-300 2800)(-425 2800);
WIRE 16 -1 (-425 2850)(-1125 2850);
FORCEPROP 0 LAST SIG_NAME FM_DB1200ZL_BCLKS_EN_N
J 0
(-1125 2860);
DISPLAY 0.617021 (-1125 2860);
PAINT ORANGE (-1125 2860);
WIRE 16 -1 (-425 2800)(-425 2850);
WIRE 16 -1 (-300 2850)(-425 2850);
WIRE 16 -1 (-300 2600)(-525 2600);
WIRE 16 -1 (-525 2600)(-525 2650);
WIRE 16 -1 (-300 2650)(-525 2650);
WIRE 16 -1 (-525 2700)(-1125 2700);
FORCEPROP 2 LAST SIG_NAME FM_CPU0_MCP_CLK_EN_N
J 0
(-1125 2710);
DISPLAY 0.617021 (-1125 2710);
PAINT ORANGE (-1125 2710);
WIRE 16 -1 (-525 2650)(-525 2700);
WIRE 16 -1 (-300 2700)(-525 2700);
WIRE 16 -1 (-3225 2650)(-3225 2575);
WIRE 16 -1 (-3225 2750)(-3225 2650);
WIRE 16 -1 (-3225 2650)(-2000 2650);
FORCEPROP 0 LAST SIG_NAME FM_DB1200_SMB_SA0
J 0
(-2525 2660);
DISPLAY 0.617021 (-2525 2660);
PAINT ORANGE (-2525 2660);
WIRE 16 -1 (-2850 2575)(-2850 2700);
WIRE 16 -1 (-2850 2700)(-2000 2700);
FORCEPROP 0 LAST SIG_NAME FM_DB1200_SMB_SA1
J 0
(-2525 2710);
DISPLAY 0.617021 (-2525 2710);
PAINT ORANGE (-2525 2710);
WIRE 16 -1 (-2850 2750)(-2850 2700);
WIRE 16 -1 (-300 3150)(-1125 3150);
FORCEPROP 2 LAST SIG_NAME SMB_HOST_STBY_LVC3_SDA_R2
J 0
(-1125 3160);
DISPLAY 0.617021 (-1125 3160);
PAINT ORANGE (-1125 3160);
WIRE 16 -1 (-2575 3325)(-2575 3400);
WIRE 16 -1 (-2575 3400)(-2725 3400);
WIRE 16 -1 (-2325 3400)(-2575 3400);
WIRE 16 -1 (-2325 3325)(-2325 3400);
WIRE 16 -1 (-300 3400)(-2325 3400);
FORCEPROP 0 LAST VOLTAGE +3.3V
J 0
(-925 3450);
DISPLAY 1.021277 (-925 3450);
PAINT SKYBLUE (-925 3450);
DISPLAY INVISIBLE (-925 3450);
FORCEPROP 0 LAST SIG_NAME P3V3_DB1200_R
J 0
(-2085 3410);
DISPLAY 0.617021 (-2085 3410);
PAINT ORANGE (-2085 3410);
FORCEPROP 2 LASTPROP $XRERR UNIQUE?
J 0
(-2325 3410);
DISPLAY 0.638298 (-2325 3410);
PAINT MONO (-2325 3410);
DISPLAY INVISIBLE (-2325 3410);
WIRE 16 -1 (1000 2650)(1975 2650);
FORCEPROP 2 LAST SIG_NAME CLK_100M_CPU0_BCLK2_R_DN
J 0
(1125 2660);
DISPLAY 0.617021 (1125 2660);
PAINT ORANGE (1125 2660);
WIRE 16 -1 (1000 2700)(1975 2700);
FORCEPROP 2 LAST SIG_NAME CLK_100M_CPU0_BCLK2_R_DP
J 0
(1125 2710);
DISPLAY 0.617021 (1125 2710);
PAINT ORANGE (1125 2710);
WIRE 16 -1 (1000 2750)(1975 2750);
FORCEPROP 2 LAST SIG_NAME CLK_100M_CPU0_PE_REFCLK_R_DN
J 0
(1125 2760);
DISPLAY 0.617021 (1125 2760);
PAINT ORANGE (1125 2760);
WIRE 16 -1 (1000 2550)(1975 2550);
FORCEPROP 2 LAST SIG_NAME CLK_100M_CPU0_BCLK1_R_DN
J 0
(1125 2560);
DISPLAY 0.617021 (1125 2560);
PAINT ORANGE (1125 2560);
WIRE 16 -1 (1000 2800)(1975 2800);
FORCEPROP 2 LAST SIG_NAME CLK_100M_CPU0_PE_REFCLK_R_DP
J 0
(1125 2810);
DISPLAY 0.617021 (1125 2810);
PAINT ORANGE (1125 2810);
WIRE 16 -1 (1000 2900)(1975 2900);
FORCEPROP 2 LAST SIG_NAME CLK_100M_CPU0_RC_REFCLK0_R_DP
J 0
(1125 2910);
DISPLAY 0.617021 (1125 2910);
PAINT ORANGE (1125 2910);
WIRE 16 -1 (1000 3050)(1975 3050);
FORCEPROP 2 LAST SIG_NAME CLK_100M_CPU1_BCLK0_R_DN
J 0
(1125 3060);
DISPLAY 0.617021 (1125 3060);
PAINT ORANGE (1125 3060);
WIRE 16 -1 (-300 3300)(-1125 3300);
FORCEPROP 0 LAST SIG_NAME FM_DB1200_SMB_SA0
J 0
(-1125 3310);
DISPLAY 0.617021 (-1125 3310);
PAINT ORANGE (-1125 3310);
WIRE 16 -1 (2450 4700)(2450 4750);
WIRE 16 -1 (2450 4750)(2450 4800);
WIRE 16 -1 (2100 4750)(2450 4750);
WIRE 16 -1 (2100 4300)(2100 4750);
FORCEPROP 2 LAST SIG_NAME P3V3_DB1200_R1
J 0
(2065 4785);
DISPLAY 0.638298 (2065 4785);
PAINT ORANGE (2065 4785);
FORCEPROP 2 LASTPROP $XRERR UNIQUE?
J 0
(1825 4785);
DISPLAY 0.638298 (1825 4785);
PAINT MONO (1825 4785);
DISPLAY INVISIBLE (1825 4785);
WIRE 16 -1 (3300 4650)(3300 4500);
WIRE 16 -1 (3300 4500)(3775 4500);
WIRE 16 -1 (2550 4500)(3300 4500);
FORCEPROP 2 LAST SIG_NAME SMB_HOST_STBY_LVC3_SDA_R2
J 0
(2615 4510);
DISPLAY 0.617021 (2615 4510);
PAINT ORANGE (2615 4510);
WIRE 16 -1 (2150 4500)(1100 4500);
FORCEPROP 2 LAST SIG_NAME SMB_HOST_STBY_LVC3_SDA
J 0
(1140 4510);
DISPLAY 0.617021 (1140 4510);
PAINT ORANGE (1140 4510);
WIRE 16 -1 (1100 4100)(1800 4100);
FORCEPROP 2 LAST SIG_NAME SMB_HOST_STBY_LVC3_SCL
J 0
(1140 4110);
DISPLAY 0.617021 (1140 4110);
PAINT ORANGE (1140 4110);
WIRE 16 -1 (1000 3000)(1975 3000);
FORCEPROP 2 LAST SIG_NAME CLK_100M_CPU0_RC_REFCLK1_R_DP
J 0
(1125 3010);
DISPLAY 0.617021 (1125 3010);
PAINT ORANGE (1125 3010);
WIRE 16 -1 (-2925 1200)(-2925 1125);
WIRE 16 -1 (-2925 1325)(-2925 1200);
WIRE 16 -1 (-1700 1200)(-2925 1200);
FORCEPROP 0 LAST SIG_NAME FM_HBW_BYPASS_LOWBW_N
J 0
(-2285 1210);
DISPLAY 0.617021 (-2285 1210);
PAINT ORANGE (-2285 1210);
WIRE 16 -1 (-2675 1250)(-2675 1125);
WIRE 16 -1 (-2675 1325)(-2675 1250);
WIRE 16 -1 (-2675 1250)(-1700 1250);
FORCEPROP 0 LAST SIG_NAME FM_100M_N
J 0
(-2285 1260);
DISPLAY 0.617021 (-2285 1260);
PAINT ORANGE (-2285 1260);
WIRE 16 -1 (200 875)(725 875);
FORCEPROP 2 LAST SIG_NAME FM_CPU0_MCP_CLK_EN_N
J 0
(240 885);
DISPLAY 0.617021 (240 885);
PAINT ORANGE (240 885);
WIRE 16 -1 (200 975)(200 875);
WIRE 16 -1 (1000 2600)(1975 2600);
FORCEPROP 2 LAST SIG_NAME CLK_100M_CPU0_BCLK1_R_DP
J 0
(1125 2610);
DISPLAY 0.617021 (1125 2610);
PAINT ORANGE (1125 2610);
WIRE 16 -1 (1000 3150)(1975 3150);
FORCEPROP 2 LAST SIG_NAME CLK_100M_CPU1_BCLK1_R_DN
J 0
(1125 3160);
DISPLAY 0.617021 (1125 3160);
PAINT ORANGE (1125 3160);
WIRE 16 -1 (1000 3250)(1975 3250);
FORCEPROP 2 LAST SIG_NAME CLK_100M_CPU1_BCLK2_R_DN
J 0
(1125 3260);
DISPLAY 0.617021 (1125 3260);
PAINT ORANGE (1125 3260);
WIRE 16 -1 (1000 3200)(1975 3200);
FORCEPROP 2 LAST SIG_NAME CLK_100M_CPU1_BCLK1_R_DP
J 0
(1125 3210);
DISPLAY 0.617021 (1125 3210);
PAINT ORANGE (1125 3210);
WIRE 16 -1 (1000 3350)(1975 3350);
FORCEPROP 2 LAST SIG_NAME CLK_100M_CPU1_PE_REFCLK_R_DN
J 0
(1125 3360);
DISPLAY 0.617021 (1125 3360);
PAINT ORANGE (1125 3360);
WIRE 16 -1 (1000 3300)(1975 3300);
FORCEPROP 2 LAST SIG_NAME CLK_100M_CPU1_BCLK2_R_DP
J 0
(1125 3310);
DISPLAY 0.617021 (1125 3310);
PAINT ORANGE (1125 3310);
WIRE 16 -1 (1000 3400)(1975 3400);
FORCEPROP 2 LAST SIG_NAME CLK_100M_CPU1_PE_REFCLK_R_DP
J 0
(1125 3410);
DISPLAY 0.617021 (1125 3410);
PAINT ORANGE (1125 3410);
WIRE 16 -1 (1000 3450)(1975 3450);
FORCEPROP 2 LAST SIG_NAME CLK_100M_CPU1_RC_REFCLK0_R_DN
J 0
(1125 3460);
DISPLAY 0.617021 (1125 3460);
PAINT ORANGE (1125 3460);
WIRE 16 -1 (1000 3600)(1975 3600);
FORCEPROP 2 LAST SIG_NAME CLK_100M_CPU1_RC_REFCLK1_R_DP
J 0
(1125 3610);
DISPLAY 0.617021 (1125 3610);
PAINT ORANGE (1125 3610);
WIRE 16 -1 (1000 3500)(1975 3500);
FORCEPROP 2 LAST SIG_NAME CLK_100M_CPU1_RC_REFCLK0_R_DP
J 0
(1125 3510);
DISPLAY 0.617021 (1125 3510);
PAINT ORANGE (1125 3510);
WIRE 16 -1 (1000 2850)(1975 2850);
FORCEPROP 2 LAST SIG_NAME CLK_100M_CPU0_RC_REFCLK0_R_DN
J 0
(1125 2860);
DISPLAY 0.617021 (1125 2860);
PAINT ORANGE (1125 2860);
WIRE 16 -1 (1000 3100)(1975 3100);
FORCEPROP 2 LAST SIG_NAME CLK_100M_CPU1_BCLK0_R_DP
J 0
(1125 3110);
DISPLAY 0.617021 (1125 3110);
PAINT ORANGE (1125 3110);
WIRE 16 -1 (1000 2950)(1975 2950);
FORCEPROP 2 LAST SIG_NAME CLK_100M_CPU0_RC_REFCLK1_R_DN
J 0
(1125 2960);
DISPLAY 0.617021 (1125 2960);
PAINT ORANGE (1125 2960);
WIRE 16 -1 (-1125 3250)(-300 3250);
FORCEPROP 0 LAST SIG_NAME FM_DB1200_SMB_SA1
J 0
(-1125 3260);
DISPLAY 0.617021 (-1125 3260);
PAINT ORANGE (-1125 3260);
WIRE 16 -1 (3650 4100)(3775 4100);
WIRE 16 -1 (3650 4650)(3650 4100);
WIRE 16 -1 (2200 4100)(3650 4100);
FORCEPROP 2 LAST SIG_NAME SMB_HOST_STBY_LVC3_SCL_R2
J 0
(2615 4110);
DISPLAY 0.617021 (2615 4110);
PAINT ORANGE (2615 4110);
WIRE 3 682 (1100 3825)(1100 3675);
WIRE 3 682 (1750 3825)(1100 3825);
WIRE 3 682 (1100 3675)(1750 3675);
WIRE 3 682 (1750 3675)(1750 3825);
DOT 1 (-525 3000);
DOT 1 (-525 2950);
DOT 1 (3700 1125);
DOT 1 (3475 1125);
DOT 1 (3275 1125);
DOT 1 (3700 675);
DOT 1 (3475 675);
DOT 1 (3275 675);
DOT 1 (3050 1125);
DOT 1 (2825 1125);
DOT 1 (2575 1125);
DOT 1 (2275 1125);
DOT 1 (3050 675);
DOT 1 (2825 675);
DOT 1 (2575 675);
DOT 1 (2275 675);
DOT 1 (1425 2250);
DOT 1 (1425 2150);
DOT 1 (1425 2200);
DOT 1 (1425 2100);
DOT 1 (1425 2050);
DOT 1 (1425 2000);
DOT 1 (1975 1125);
DOT 1 (1425 1950);
DOT 1 (-825 3700);
DOT 1 (-825 3750);
DOT 1 (-825 3650);
DOT 1 (-825 3550);
DOT 1 (-825 3600);
DOT 1 (-825 3500);
DOT 1 (-425 2850);
DOT 1 (-425 2800);
DOT 1 (-425 2750);
DOT 1 (-425 2500);
DOT 1 (-425 2550);
DOT 1 (-525 2700);
DOT 1 (-525 2650);
DOT 1 (-2325 3400);
DOT 1 (-2575 3400);
DOT 1 (-2850 2700);
DOT 1 (-2850 2225);
DOT 1 (-3225 3050);
DOT 1 (-3225 2650);
DOT 1 (-2925 1650);
DOT 1 (-2675 1250);
DOT 1 (-2925 1200);
DOT 1 (-2675 850);
DOT 1 (-1550 3700);
DOT 1 (-1800 4125);
DOT 1 (-1550 4125);
DOT 1 (3650 4100);
DOT 1 (3650 4950);
DOT 1 (2450 4750);
DOT 1 (3300 4500);
DOT 1 (-950 2200);
DOT 1 (-1650 1850);
DOT 1 (-2325 3000);
DOT 1 (-1650 2200);
DOT 1 (-750 1300);
DOT 1 (-125 1300);
FORCENOTE
TP FAB1 CHANGE CONNECTION 0318
(-1975 2450) 0;
DISPLAY LEFT (-1975 2450);
DISPLAY 1.021277 (-1975 2450);
PAINT RED (-1975 2450);
FORCENOTE
TP FAB1 NOPOP RES 0318
(-2050 1775) 0;
DISPLAY LEFT (-2050 1775);
DISPLAY 1.021277 (-2050 1775);
PAINT RED (-2050 1775);
FORCENOTE
TP FAB1 ADD ISOLATION CIRCUIT 0317
(2475 3850) 0;
DISPLAY LEFT (2475 3850);
DISPLAY 1.021277 (2475 3850);
PAINT RED (2475 3850);
FORCENOTE
ROOM=DB1200Z
(-3700 375) 0;
DISPLAY LEFT (-3700 375);
DISPLAY 1.021277 (-3700 375);
PAINT PURPLE (-3700 375);
FORCENOTE
BOM_COST=SYS_CLOCK
(-3700 325) 0;
DISPLAY LEFT (-3700 325);
DISPLAY 1.021277 (-3700 325);
PAINT PURPLE (-3700 325);
FORCENOTE
TP FAB1 DEL NETS 0309
(1100 3850) 0;
DISPLAY LEFT (1100 3850);
DISPLAY 1.021277 (1100 3850);
PAINT RED (1100 3850);
FORCENOTE
TP FAB1 ADD MOS 0318
(-1300 1600) 0;
DISPLAY LEFT (-1300 1600);
DISPLAY 1.021277 (-1300 1600);
PAINT RED (-1300 1600);
FORCENOTE
SMBUS ADDRESS: 0XD8
(-250 1600) 0;
DISPLAY LEFT (-250 1600);
DISPLAY 1.021277 (-250 1600);
PAINT PURPLE (-250 1600);
FORCENOTE
TP FAB5 CHANGE RES FROM 4.75K TO 1K 20170508
(-1050 800) 0;
DISPLAY LEFT (-1050 800);
DISPLAY 0.638298 (-1050 800);
PAINT RED (-1050 800);
QUIT
